FILE_TYPE = MACRO_DRAWING;
SET COLOR_WIRE YELLOW;
SET COLOR_PROP ORANGE;
SET COLOR_DOT WHITE;
SET COLOR_ARC YELLOW;
SET COLOR_BODY GREEN;
SET COLOR_NOTE PURPLE;
SET PROP_DISPLAY VALUE;
SET PAGE_NUMBER P169;
FORCEADD OFFPAGE..1
(-2650 1600);
FORCEPROP 2 LAST $XR0 28 
J 0
(-2901 1600);
DISPLAY 0.638298 (-2901 1600);
PAINT MONO (-2901 1600);
FORCEPROP 2 LAST CDS_LIB standard
J 0
(-2650 1600);
DISPLAY INVISIBLE (-2650 1600);
FORCEPROP 1 LAST OFFPAGE TRUE
J 0
(-2325 1475);
DISPLAY 0.872340 (-2325 1475);
DISPLAY INVISIBLE (-2325 1475);
FORCEPROP 1 LAST COMMENT_BODY TRUE
J 0
(-2525 1500);
DISPLAY 0.872340 (-2525 1500);
PAINT GREEN (-2525 1500);
DISPLAY INVISIBLE (-2525 1500);
FORCEPROP 2 LAST PATH I1
J 0
(-2600 1675);
DISPLAY 1.021277 (-2600 1675);
DISPLAY INVISIBLE (-2600 1675);
FORCEADD TAP..1
R 2
(-1700 725);
FORCEPROP 3 LASTPIN (-1650 725) SIG_NAME DMI_CPU0_PCH_TX_DP<3>
J 0
(-1640 735);
DISPLAY 0.659574 (-1640 735);
PAINT MONO (-1640 735);
DISPLAY INVISIBLE (-1640 735);
FORCEPROP 1 LASTPIN (-1650 725) BN 3
J 2
(-1638 733);
DISPLAY 0.680851 (-1638 733);
PAINT GREEN (-1638 733);
FORCEPROP 2 LAST CDS_LIB standard
J 0
(-1700 725);
DISPLAY INVISIBLE (-1700 725);
FORCEPROP 1 LAST BODY_TYPE PLUMBING
J 2
(-1700 775);
DISPLAY 0.872340 (-1700 775);
PAINT GREEN (-1700 775);
DISPLAY INVISIBLE (-1700 775);
FORCEPROP 1 LAST HDL_TAP TRUE
J 2
(-2025 600);
DISPLAY 0.872340 (-2025 600);
DISPLAY INVISIBLE (-2025 600);
FORCEPROP 1 LAST PATH I10
J 2
(-1698 725);
DISPLAY 0.872340 (-1698 725);
PAINT GREEN (-1698 725);
DISPLAY INVISIBLE (-1698 725);
FORCEADD TAP..1
(25 -1475);
FORCEPROP 3 LASTPIN (-25 -1475) SIG_NAME DMI_CPU0_PCH_RX_C_DP<7>
J 0
(-15 -1465);
DISPLAY 0.659574 (-15 -1465);
PAINT MONO (-15 -1465);
DISPLAY INVISIBLE (-15 -1465);
FORCEPROP 1 LASTPIN (-25 -1475) BN 7
J 0
(-37 -1467);
DISPLAY 0.680851 (-37 -1467);
PAINT GREEN (-37 -1467);
FORCEPROP 2 LAST CDS_LIB standard
J 0
(25 -1475);
DISPLAY INVISIBLE (25 -1475);
FORCEPROP 1 LAST BODY_TYPE PLUMBING
J 0
(25 -1425);
DISPLAY 0.872340 (25 -1425);
PAINT GREEN (25 -1425);
DISPLAY INVISIBLE (25 -1425);
FORCEPROP 1 LAST HDL_TAP TRUE
J 0
(350 -1600);
DISPLAY 0.872340 (350 -1600);
DISPLAY INVISIBLE (350 -1600);
FORCEPROP 1 LAST PATH I100
J 0
(23 -1475);
DISPLAY 0.872340 (23 -1475);
PAINT GREEN (23 -1475);
DISPLAY INVISIBLE (23 -1475);
FORCEADD TAP..1
(25 -1675);
FORCEPROP 3 LASTPIN (-25 -1675) SIG_NAME DMI_CPU0_PCH_RX_C_DP<6>
J 0
(-15 -1665);
DISPLAY 0.659574 (-15 -1665);
PAINT MONO (-15 -1665);
DISPLAY INVISIBLE (-15 -1665);
FORCEPROP 1 LASTPIN (-25 -1675) BN 6
J 0
(-37 -1667);
DISPLAY 0.680851 (-37 -1667);
PAINT GREEN (-37 -1667);
FORCEPROP 2 LAST CDS_LIB standard
J 0
(25 -1675);
DISPLAY INVISIBLE (25 -1675);
FORCEPROP 1 LAST BODY_TYPE PLUMBING
J 0
(25 -1625);
DISPLAY 0.872340 (25 -1625);
PAINT GREEN (25 -1625);
DISPLAY INVISIBLE (25 -1625);
FORCEPROP 1 LAST HDL_TAP TRUE
J 0
(350 -1800);
DISPLAY 0.872340 (350 -1800);
DISPLAY INVISIBLE (350 -1800);
FORCEPROP 1 LAST PATH I101
J 0
(23 -1675);
DISPLAY 0.872340 (23 -1675);
PAINT GREEN (23 -1675);
DISPLAY INVISIBLE (23 -1675);
FORCEADD TAP..1
(25 -1875);
FORCEPROP 3 LASTPIN (-25 -1875) SIG_NAME DMI_CPU0_PCH_RX_C_DP<5>
J 0
(-15 -1865);
DISPLAY 0.659574 (-15 -1865);
PAINT MONO (-15 -1865);
DISPLAY INVISIBLE (-15 -1865);
FORCEPROP 1 LASTPIN (-25 -1875) BN 5
J 0
(-37 -1867);
DISPLAY 0.680851 (-37 -1867);
PAINT GREEN (-37 -1867);
FORCEPROP 2 LAST CDS_LIB standard
J 0
(25 -1875);
DISPLAY INVISIBLE (25 -1875);
FORCEPROP 1 LAST BODY_TYPE PLUMBING
J 0
(25 -1825);
DISPLAY 0.872340 (25 -1825);
PAINT GREEN (25 -1825);
DISPLAY INVISIBLE (25 -1825);
FORCEPROP 1 LAST HDL_TAP TRUE
J 0
(350 -2000);
DISPLAY 0.872340 (350 -2000);
DISPLAY INVISIBLE (350 -2000);
FORCEPROP 1 LAST PATH I102
J 0
(23 -1875);
DISPLAY 0.872340 (23 -1875);
PAINT GREEN (23 -1875);
DISPLAY INVISIBLE (23 -1875);
FORCEADD TAP..1
(-175 -1825);
FORCEPROP 3 LASTPIN (-225 -1825) SIG_NAME DMI_CPU0_PCH_RX_C_DN<5>
J 0
(-215 -1815);
DISPLAY 0.659574 (-215 -1815);
PAINT MONO (-215 -1815);
DISPLAY INVISIBLE (-215 -1815);
FORCEPROP 1 LASTPIN (-225 -1825) BN 5
J 0
(-237 -1817);
DISPLAY 0.680851 (-237 -1817);
PAINT GREEN (-237 -1817);
FORCEPROP 2 LAST CDS_LIB standard
J 0
(-175 -1825);
DISPLAY INVISIBLE (-175 -1825);
FORCEPROP 1 LAST BODY_TYPE PLUMBING
J 0
(-175 -1775);
DISPLAY 0.872340 (-175 -1775);
PAINT GREEN (-175 -1775);
DISPLAY INVISIBLE (-175 -1775);
FORCEPROP 1 LAST HDL_TAP TRUE
J 0
(150 -1950);
DISPLAY 0.872340 (150 -1950);
DISPLAY INVISIBLE (150 -1950);
FORCEPROP 1 LAST PATH I103
J 0
(-177 -1825);
DISPLAY 0.872340 (-177 -1825);
PAINT GREEN (-177 -1825);
DISPLAY INVISIBLE (-177 -1825);
FORCEADD TAP..1
(-175 -1625);
FORCEPROP 3 LASTPIN (-225 -1625) SIG_NAME DMI_CPU0_PCH_RX_C_DN<6>
J 0
(-215 -1615);
DISPLAY 0.659574 (-215 -1615);
PAINT MONO (-215 -1615);
DISPLAY INVISIBLE (-215 -1615);
FORCEPROP 1 LASTPIN (-225 -1625) BN 6
J 0
(-237 -1617);
DISPLAY 0.680851 (-237 -1617);
PAINT GREEN (-237 -1617);
FORCEPROP 2 LAST CDS_LIB standard
J 0
(-175 -1625);
DISPLAY INVISIBLE (-175 -1625);
FORCEPROP 1 LAST BODY_TYPE PLUMBING
J 0
(-175 -1575);
DISPLAY 0.872340 (-175 -1575);
PAINT GREEN (-175 -1575);
DISPLAY INVISIBLE (-175 -1575);
FORCEPROP 1 LAST HDL_TAP TRUE
J 0
(150 -1750);
DISPLAY 0.872340 (150 -1750);
DISPLAY INVISIBLE (150 -1750);
FORCEPROP 1 LAST PATH I104
J 0
(-177 -1625);
DISPLAY 0.872340 (-177 -1625);
PAINT GREEN (-177 -1625);
DISPLAY INVISIBLE (-177 -1625);
FORCEADD TAP..1
(25 -2075);
FORCEPROP 3 LASTPIN (-25 -2075) SIG_NAME DMI_CPU0_PCH_RX_C_DP<4>
J 0
(-15 -2065);
DISPLAY 0.659574 (-15 -2065);
PAINT MONO (-15 -2065);
DISPLAY INVISIBLE (-15 -2065);
FORCEPROP 1 LASTPIN (-25 -2075) BN 4
J 0
(-37 -2067);
DISPLAY 0.680851 (-37 -2067);
PAINT GREEN (-37 -2067);
FORCEPROP 2 LAST CDS_LIB standard
J 0
(25 -2075);
DISPLAY INVISIBLE (25 -2075);
FORCEPROP 1 LAST BODY_TYPE PLUMBING
J 0
(25 -2025);
DISPLAY 0.872340 (25 -2025);
PAINT GREEN (25 -2025);
DISPLAY INVISIBLE (25 -2025);
FORCEPROP 1 LAST HDL_TAP TRUE
J 0
(350 -2200);
DISPLAY 0.872340 (350 -2200);
DISPLAY INVISIBLE (350 -2200);
FORCEPROP 1 LAST PATH I105
J 0
(23 -2075);
DISPLAY 0.872340 (23 -2075);
PAINT GREEN (23 -2075);
DISPLAY INVISIBLE (23 -2075);
FORCEADD TAP..1
(25 -2475);
FORCEPROP 3 LASTPIN (-25 -2475) SIG_NAME DMI_CPU0_PCH_RX_C_DP<2>
J 0
(-15 -2465);
DISPLAY 0.659574 (-15 -2465);
PAINT MONO (-15 -2465);
DISPLAY INVISIBLE (-15 -2465);
FORCEPROP 1 LASTPIN (-25 -2475) BN 2
J 0
(-37 -2467);
DISPLAY 0.680851 (-37 -2467);
PAINT GREEN (-37 -2467);
FORCEPROP 2 LAST CDS_LIB standard
J 0
(25 -2475);
DISPLAY INVISIBLE (25 -2475);
FORCEPROP 1 LAST BODY_TYPE PLUMBING
J 0
(25 -2425);
DISPLAY 0.872340 (25 -2425);
PAINT GREEN (25 -2425);
DISPLAY INVISIBLE (25 -2425);
FORCEPROP 1 LAST HDL_TAP TRUE
J 0
(350 -2600);
DISPLAY 0.872340 (350 -2600);
DISPLAY INVISIBLE (350 -2600);
FORCEPROP 1 LAST PATH I106
J 0
(23 -2475);
DISPLAY 0.872340 (23 -2475);
PAINT GREEN (23 -2475);
DISPLAY INVISIBLE (23 -2475);
FORCEADD TAP..1
(25 -2275);
FORCEPROP 3 LASTPIN (-25 -2275) SIG_NAME DMI_CPU0_PCH_RX_C_DP<3>
J 0
(-15 -2265);
DISPLAY 0.659574 (-15 -2265);
PAINT MONO (-15 -2265);
DISPLAY INVISIBLE (-15 -2265);
FORCEPROP 1 LASTPIN (-25 -2275) BN 3
J 0
(-37 -2267);
DISPLAY 0.680851 (-37 -2267);
PAINT GREEN (-37 -2267);
FORCEPROP 2 LAST CDS_LIB standard
J 0
(25 -2275);
DISPLAY INVISIBLE (25 -2275);
FORCEPROP 1 LAST BODY_TYPE PLUMBING
J 0
(25 -2225);
DISPLAY 0.872340 (25 -2225);
PAINT GREEN (25 -2225);
DISPLAY INVISIBLE (25 -2225);
FORCEPROP 1 LAST HDL_TAP TRUE
J 0
(350 -2400);
DISPLAY 0.872340 (350 -2400);
DISPLAY INVISIBLE (350 -2400);
FORCEPROP 1 LAST PATH I107
J 0
(23 -2275);
DISPLAY 0.872340 (23 -2275);
PAINT GREEN (23 -2275);
DISPLAY INVISIBLE (23 -2275);
FORCEADD TAP..1
(-175 -2025);
FORCEPROP 3 LASTPIN (-225 -2025) SIG_NAME DMI_CPU0_PCH_RX_C_DN<4>
J 0
(-215 -2015);
DISPLAY 0.659574 (-215 -2015);
PAINT MONO (-215 -2015);
DISPLAY INVISIBLE (-215 -2015);
FORCEPROP 1 LASTPIN (-225 -2025) BN 4
J 0
(-237 -2017);
DISPLAY 0.680851 (-237 -2017);
PAINT GREEN (-237 -2017);
FORCEPROP 2 LAST CDS_LIB standard
J 0
(-175 -2025);
DISPLAY INVISIBLE (-175 -2025);
FORCEPROP 1 LAST BODY_TYPE PLUMBING
J 0
(-175 -1975);
DISPLAY 0.872340 (-175 -1975);
PAINT GREEN (-175 -1975);
DISPLAY INVISIBLE (-175 -1975);
FORCEPROP 1 LAST HDL_TAP TRUE
J 0
(150 -2150);
DISPLAY 0.872340 (150 -2150);
DISPLAY INVISIBLE (150 -2150);
FORCEPROP 1 LAST PATH I108
J 0
(-177 -2025);
DISPLAY 0.872340 (-177 -2025);
PAINT GREEN (-177 -2025);
DISPLAY INVISIBLE (-177 -2025);
FORCEADD TAP..1
(-175 -2425);
FORCEPROP 3 LASTPIN (-225 -2425) SIG_NAME DMI_CPU0_PCH_RX_C_DN<2>
J 0
(-215 -2415);
DISPLAY 0.659574 (-215 -2415);
PAINT MONO (-215 -2415);
DISPLAY INVISIBLE (-215 -2415);
FORCEPROP 1 LASTPIN (-225 -2425) BN 2
J 0
(-237 -2417);
DISPLAY 0.680851 (-237 -2417);
PAINT GREEN (-237 -2417);
FORCEPROP 2 LAST CDS_LIB standard
J 0
(-175 -2425);
DISPLAY INVISIBLE (-175 -2425);
FORCEPROP 1 LAST BODY_TYPE PLUMBING
J 0
(-175 -2375);
DISPLAY 0.872340 (-175 -2375);
PAINT GREEN (-175 -2375);
DISPLAY INVISIBLE (-175 -2375);
FORCEPROP 1 LAST HDL_TAP TRUE
J 0
(150 -2550);
DISPLAY 0.872340 (150 -2550);
DISPLAY INVISIBLE (150 -2550);
FORCEPROP 1 LAST PATH I109
J 0
(-177 -2425);
DISPLAY 0.872340 (-177 -2425);
PAINT GREEN (-177 -2425);
DISPLAY INVISIBLE (-177 -2425);
FORCEADD TAP..1
R 2
(-1700 925);
FORCEPROP 3 LASTPIN (-1650 925) SIG_NAME DMI_CPU0_PCH_TX_DP<4>
J 0
(-1640 935);
DISPLAY 0.659574 (-1640 935);
PAINT MONO (-1640 935);
DISPLAY INVISIBLE (-1640 935);
FORCEPROP 1 LASTPIN (-1650 925) BN 4
J 2
(-1638 933);
DISPLAY 0.680851 (-1638 933);
PAINT GREEN (-1638 933);
FORCEPROP 2 LAST CDS_LIB standard
J 0
(-1700 925);
DISPLAY INVISIBLE (-1700 925);
FORCEPROP 1 LAST BODY_TYPE PLUMBING
J 2
(-1700 975);
DISPLAY 0.872340 (-1700 975);
PAINT GREEN (-1700 975);
DISPLAY INVISIBLE (-1700 975);
FORCEPROP 1 LAST HDL_TAP TRUE
J 2
(-2025 800);
DISPLAY 0.872340 (-2025 800);
DISPLAY INVISIBLE (-2025 800);
FORCEPROP 1 LAST PATH I11
J 2
(-1698 925);
DISPLAY 0.872340 (-1698 925);
PAINT GREEN (-1698 925);
DISPLAY INVISIBLE (-1698 925);
FORCEADD TAP..1
(-175 -2225);
FORCEPROP 3 LASTPIN (-225 -2225) SIG_NAME DMI_CPU0_PCH_RX_C_DN<3>
J 0
(-215 -2215);
DISPLAY 0.659574 (-215 -2215);
PAINT MONO (-215 -2215);
DISPLAY INVISIBLE (-215 -2215);
FORCEPROP 1 LASTPIN (-225 -2225) BN 3
J 0
(-237 -2217);
DISPLAY 0.680851 (-237 -2217);
PAINT GREEN (-237 -2217);
FORCEPROP 2 LAST CDS_LIB standard
J 0
(-175 -2225);
DISPLAY INVISIBLE (-175 -2225);
FORCEPROP 1 LAST BODY_TYPE PLUMBING
J 0
(-175 -2175);
DISPLAY 0.872340 (-175 -2175);
PAINT GREEN (-175 -2175);
DISPLAY INVISIBLE (-175 -2175);
FORCEPROP 1 LAST HDL_TAP TRUE
J 0
(150 -2350);
DISPLAY 0.872340 (150 -2350);
DISPLAY INVISIBLE (150 -2350);
FORCEPROP 1 LAST PATH I110
J 0
(-177 -2225);
DISPLAY 0.872340 (-177 -2225);
PAINT GREEN (-177 -2225);
DISPLAY INVISIBLE (-177 -2225);
FORCEADD TAP..1
(25 -2675);
FORCEPROP 3 LASTPIN (-25 -2675) SIG_NAME DMI_CPU0_PCH_RX_C_DP<1>
J 0
(-15 -2665);
DISPLAY 0.659574 (-15 -2665);
PAINT MONO (-15 -2665);
DISPLAY INVISIBLE (-15 -2665);
FORCEPROP 1 LASTPIN (-25 -2675) BN 1
J 0
(-37 -2667);
DISPLAY 0.680851 (-37 -2667);
PAINT GREEN (-37 -2667);
FORCEPROP 2 LAST CDS_LIB standard
J 0
(25 -2675);
DISPLAY INVISIBLE (25 -2675);
FORCEPROP 1 LAST BODY_TYPE PLUMBING
J 0
(25 -2625);
DISPLAY 0.872340 (25 -2625);
PAINT GREEN (25 -2625);
DISPLAY INVISIBLE (25 -2625);
FORCEPROP 1 LAST HDL_TAP TRUE
J 0
(350 -2800);
DISPLAY 0.872340 (350 -2800);
DISPLAY INVISIBLE (350 -2800);
FORCEPROP 1 LAST PATH I111
J 0
(23 -2675);
DISPLAY 0.872340 (23 -2675);
PAINT GREEN (23 -2675);
DISPLAY INVISIBLE (23 -2675);
FORCEADD TAP..1
(25 -2875);
FORCEPROP 3 LASTPIN (-25 -2875) SIG_NAME DMI_CPU0_PCH_RX_C_DP<0>
J 0
(-15 -2865);
DISPLAY 0.659574 (-15 -2865);
PAINT MONO (-15 -2865);
DISPLAY INVISIBLE (-15 -2865);
FORCEPROP 1 LASTPIN (-25 -2875) BN 0
J 0
(-37 -2867);
DISPLAY 0.680851 (-37 -2867);
PAINT GREEN (-37 -2867);
FORCEPROP 2 LAST CDS_LIB standard
J 0
(25 -2875);
DISPLAY INVISIBLE (25 -2875);
FORCEPROP 1 LAST BODY_TYPE PLUMBING
J 0
(25 -2825);
DISPLAY 0.872340 (25 -2825);
PAINT GREEN (25 -2825);
DISPLAY INVISIBLE (25 -2825);
FORCEPROP 1 LAST HDL_TAP TRUE
J 0
(350 -3000);
DISPLAY 0.872340 (350 -3000);
DISPLAY INVISIBLE (350 -3000);
FORCEPROP 1 LAST PATH I112
J 0
(23 -2875);
DISPLAY 0.872340 (23 -2875);
PAINT GREEN (23 -2875);
DISPLAY INVISIBLE (23 -2875);
FORCEADD Q_CAP_DIFFBUS..2
R 2
(-725 -1425);
FORCEPROP 1 LAST PART_NUMBER SP_CH4221MEE01
J 2
(-841 -1337);
DISPLAY 0.574468 (-841 -1337);
PAINT GREEN (-841 -1337);
DISPLAY INVISIBLE (-841 -1337);
FORCEPROP 2 LAST VALUE DIFF BUS_0.22UF
J 2
(-875 -1425);
DISPLAY 0.553191 (-875 -1425);
FORCEPROP 1 LAST $LOCATION C155
J 2
(-491 -1408);
DISPLAY 0.723404 (-491 -1408);
PAINT GREEN (-491 -1408);
FORCEPROP 2 LASTPIN (-650 -1425) $PN 1
J 0
(-640 -1415);
DISPLAY 0.808511 (-640 -1415);
FORCEPROP 2 LASTPIN (-800 -1425) $PN 2
J 2
(-810 -1415);
DISPLAY 0.808511 (-810 -1415);
FORCEPROP 2 LAST TOLERANCE 20%
J 2
(-800 -1375);
DISPLAY 0.553191 (-800 -1375);
DISPLAY INVISIBLE (-800 -1375);
FORCEPROP 2 LAST PACK_TYPE C0201
J 2
(-900 -1375);
DISPLAY 0.553191 (-900 -1375);
DISPLAY INVISIBLE (-900 -1375);
FORCEPROP 1 LAST MATERIAL X6S
J 2
(-716 -1346);
DISPLAY 0.574468 (-716 -1346);
PAINT GREEN (-716 -1346);
DISPLAY INVISIBLE (-716 -1346);
FORCEPROP 2 LAST VOLTAGE 6.3V
J 2
(-1075 -1375);
DISPLAY 0.553191 (-1075 -1375);
DISPLAY INVISIBLE (-1075 -1375);
FORCEPROP 2 LAST CDS_LIB pure_quanta
J 2
(-725 -1425);
DISPLAY INVISIBLE (-725 -1425);
FORCEPROP 1 LAST CDS_LMAN_SYM_OUTLINE -25,50,25,-50
J 2
(-725 -1425);
DISPLAY 0.468085 (-725 -1425);
PAINT GREEN (-725 -1425);
DISPLAY INVISIBLE (-725 -1425);
FORCEPROP 1 LAST PIN_NAMES_ROTATE TRUE
J 2
(-725 -1425);
DISPLAY 0.489362 (-725 -1425);
PAINT GREEN (-725 -1425);
DISPLAY INVISIBLE (-725 -1425);
FORCEPROP 1 LAST PATH I113
J 2
(-725 -1425);
DISPLAY 0.723404 (-725 -1425);
DISPLAY INVISIBLE (-725 -1425);
FORCEPROP 1 LAST $LOCATION C155
J 0
(-475 -1350);
DISPLAY 1.021277 (-475 -1350);
DISPLAY INVISIBLE (-475 -1350);
FORCEPROP 2 LAST CDS_LOCATION C155
J 0
(-475 -1350);
DISPLAY 1.021277 (-475 -1350);
DISPLAY INVISIBLE (-475 -1350);
FORCEPROP 2 LAST $SEC 1
J 2
(-550 -1350);
DISPLAY 0.680851 (-550 -1350);
PAINT MONO (-550 -1350);
DISPLAY INVISIBLE (-550 -1350);
FORCEPROP 2 LAST CDS_SEC 1
J 2
(-550 -1350);
DISPLAY 0.680851 (-550 -1350);
DISPLAY INVISIBLE (-550 -1350);
FORCEADD Q_CAP_DIFFBUS..2
R 2
(-725 -1475);
FORCEPROP 1 LAST PART_NUMBER SP_CH4221MEE01
J 2
(-841 -1387);
DISPLAY 0.574468 (-841 -1387);
PAINT GREEN (-841 -1387);
DISPLAY INVISIBLE (-841 -1387);
FORCEPROP 2 LAST VALUE DIFF BUS_0.22UF
J 2
(-875 -1475);
DISPLAY 0.553191 (-875 -1475);
FORCEPROP 1 LAST $LOCATION C156
J 2
(-491 -1458);
DISPLAY 0.723404 (-491 -1458);
PAINT GREEN (-491 -1458);
FORCEPROP 2 LASTPIN (-650 -1475) $PN 1
J 0
(-640 -1465);
DISPLAY 0.808511 (-640 -1465);
FORCEPROP 2 LASTPIN (-800 -1475) $PN 2
J 2
(-810 -1465);
DISPLAY 0.808511 (-810 -1465);
FORCEPROP 2 LAST TOLERANCE 20%
J 2
(-800 -1425);
DISPLAY 0.553191 (-800 -1425);
DISPLAY INVISIBLE (-800 -1425);
FORCEPROP 2 LAST PACK_TYPE C0201
J 2
(-900 -1425);
DISPLAY 0.553191 (-900 -1425);
DISPLAY INVISIBLE (-900 -1425);
FORCEPROP 1 LAST MATERIAL X6S
J 2
(-716 -1396);
DISPLAY 0.574468 (-716 -1396);
PAINT GREEN (-716 -1396);
DISPLAY INVISIBLE (-716 -1396);
FORCEPROP 2 LAST VOLTAGE 6.3V
J 2
(-1075 -1425);
DISPLAY 0.553191 (-1075 -1425);
DISPLAY INVISIBLE (-1075 -1425);
FORCEPROP 1 LAST CDS_LMAN_SYM_OUTLINE -25,50,25,-50
J 2
(-725 -1475);
DISPLAY 0.468085 (-725 -1475);
PAINT GREEN (-725 -1475);
DISPLAY INVISIBLE (-725 -1475);
FORCEPROP 2 LAST CDS_LIB pure_quanta
J 2
(-725 -1475);
DISPLAY INVISIBLE (-725 -1475);
FORCEPROP 1 LAST PIN_NAMES_ROTATE TRUE
J 2
(-725 -1475);
DISPLAY 0.489362 (-725 -1475);
PAINT GREEN (-725 -1475);
DISPLAY INVISIBLE (-725 -1475);
FORCEPROP 1 LAST PATH I114
J 2
(-725 -1475);
DISPLAY 0.723404 (-725 -1475);
DISPLAY INVISIBLE (-725 -1475);
FORCEPROP 1 LAST $LOCATION C156
J 0
(-475 -1400);
DISPLAY 1.021277 (-475 -1400);
DISPLAY INVISIBLE (-475 -1400);
FORCEPROP 2 LAST CDS_LOCATION C156
J 0
(-475 -1400);
DISPLAY 1.021277 (-475 -1400);
DISPLAY INVISIBLE (-475 -1400);
FORCEPROP 2 LAST $SEC 1
J 2
(-550 -1400);
DISPLAY 0.680851 (-550 -1400);
PAINT MONO (-550 -1400);
DISPLAY INVISIBLE (-550 -1400);
FORCEPROP 2 LAST CDS_SEC 1
J 2
(-550 -1400);
DISPLAY 0.680851 (-550 -1400);
DISPLAY INVISIBLE (-550 -1400);
FORCEADD Q_CAP_DIFFBUS..2
R 2
(-725 -1625);
FORCEPROP 1 LAST PART_NUMBER SP_CH4221MEE01
J 2
(-841 -1537);
DISPLAY 0.574468 (-841 -1537);
PAINT GREEN (-841 -1537);
DISPLAY INVISIBLE (-841 -1537);
FORCEPROP 2 LAST VALUE DIFF BUS_0.22UF
J 2
(-875 -1625);
DISPLAY 0.553191 (-875 -1625);
FORCEPROP 1 LAST $LOCATION C157
J 2
(-491 -1608);
DISPLAY 0.723404 (-491 -1608);
PAINT GREEN (-491 -1608);
FORCEPROP 2 LASTPIN (-650 -1625) $PN 1
J 0
(-640 -1615);
DISPLAY 0.808511 (-640 -1615);
FORCEPROP 2 LASTPIN (-800 -1625) $PN 2
J 2
(-810 -1615);
DISPLAY 0.808511 (-810 -1615);
FORCEPROP 2 LAST TOLERANCE 20%
J 2
(-800 -1575);
DISPLAY 0.553191 (-800 -1575);
DISPLAY INVISIBLE (-800 -1575);
FORCEPROP 2 LAST PACK_TYPE C0201
J 2
(-900 -1575);
DISPLAY 0.553191 (-900 -1575);
DISPLAY INVISIBLE (-900 -1575);
FORCEPROP 1 LAST MATERIAL X6S
J 2
(-716 -1546);
DISPLAY 0.574468 (-716 -1546);
PAINT GREEN (-716 -1546);
DISPLAY INVISIBLE (-716 -1546);
FORCEPROP 2 LAST VOLTAGE 6.3V
J 2
(-1075 -1575);
DISPLAY 0.553191 (-1075 -1575);
DISPLAY INVISIBLE (-1075 -1575);
FORCEPROP 1 LAST CDS_LMAN_SYM_OUTLINE -25,50,25,-50
J 2
(-725 -1625);
DISPLAY 0.468085 (-725 -1625);
PAINT GREEN (-725 -1625);
DISPLAY INVISIBLE (-725 -1625);
FORCEPROP 2 LAST CDS_LIB pure_quanta
J 2
(-725 -1625);
DISPLAY INVISIBLE (-725 -1625);
FORCEPROP 1 LAST PIN_NAMES_ROTATE TRUE
J 2
(-725 -1625);
DISPLAY 0.489362 (-725 -1625);
PAINT GREEN (-725 -1625);
DISPLAY INVISIBLE (-725 -1625);
FORCEPROP 1 LAST PATH I115
J 2
(-725 -1625);
DISPLAY 0.723404 (-725 -1625);
DISPLAY INVISIBLE (-725 -1625);
FORCEPROP 1 LAST $LOCATION C157
J 0
(-475 -1550);
DISPLAY 1.021277 (-475 -1550);
DISPLAY INVISIBLE (-475 -1550);
FORCEPROP 2 LAST CDS_LOCATION C157
J 0
(-475 -1550);
DISPLAY 1.021277 (-475 -1550);
DISPLAY INVISIBLE (-475 -1550);
FORCEPROP 2 LAST $SEC 1
J 2
(-550 -1550);
DISPLAY 0.680851 (-550 -1550);
PAINT MONO (-550 -1550);
DISPLAY INVISIBLE (-550 -1550);
FORCEPROP 2 LAST CDS_SEC 1
J 2
(-550 -1550);
DISPLAY 0.680851 (-550 -1550);
DISPLAY INVISIBLE (-550 -1550);
FORCEADD Q_CAP_DIFFBUS..2
R 2
(-725 -1675);
FORCEPROP 1 LAST PART_NUMBER SP_CH4221MEE01
J 2
(-841 -1587);
DISPLAY 0.574468 (-841 -1587);
PAINT GREEN (-841 -1587);
DISPLAY INVISIBLE (-841 -1587);
FORCEPROP 2 LAST VALUE DIFF BUS_0.22UF
J 2
(-875 -1675);
DISPLAY 0.553191 (-875 -1675);
FORCEPROP 1 LAST $LOCATION C158
J 2
(-491 -1658);
DISPLAY 0.723404 (-491 -1658);
PAINT GREEN (-491 -1658);
FORCEPROP 2 LASTPIN (-650 -1675) $PN 1
J 0
(-640 -1665);
DISPLAY 0.808511 (-640 -1665);
FORCEPROP 2 LASTPIN (-800 -1675) $PN 2
J 2
(-810 -1665);
DISPLAY 0.808511 (-810 -1665);
FORCEPROP 2 LAST TOLERANCE 20%
J 2
(-800 -1625);
DISPLAY 0.553191 (-800 -1625);
DISPLAY INVISIBLE (-800 -1625);
FORCEPROP 2 LAST PACK_TYPE C0201
J 2
(-900 -1625);
DISPLAY 0.553191 (-900 -1625);
DISPLAY INVISIBLE (-900 -1625);
FORCEPROP 1 LAST MATERIAL X6S
J 2
(-716 -1596);
DISPLAY 0.574468 (-716 -1596);
PAINT GREEN (-716 -1596);
DISPLAY INVISIBLE (-716 -1596);
FORCEPROP 2 LAST VOLTAGE 6.3V
J 2
(-1075 -1625);
DISPLAY 0.553191 (-1075 -1625);
DISPLAY INVISIBLE (-1075 -1625);
FORCEPROP 1 LAST CDS_LMAN_SYM_OUTLINE -25,50,25,-50
J 2
(-725 -1675);
DISPLAY 0.468085 (-725 -1675);
PAINT GREEN (-725 -1675);
DISPLAY INVISIBLE (-725 -1675);
FORCEPROP 2 LAST CDS_LIB pure_quanta
J 2
(-725 -1675);
DISPLAY INVISIBLE (-725 -1675);
FORCEPROP 1 LAST PIN_NAMES_ROTATE TRUE
J 2
(-725 -1675);
DISPLAY 0.489362 (-725 -1675);
PAINT GREEN (-725 -1675);
DISPLAY INVISIBLE (-725 -1675);
FORCEPROP 1 LAST PATH I116
J 2
(-725 -1675);
DISPLAY 0.723404 (-725 -1675);
DISPLAY INVISIBLE (-725 -1675);
FORCEPROP 1 LAST $LOCATION C158
J 0
(-475 -1600);
DISPLAY 1.021277 (-475 -1600);
DISPLAY INVISIBLE (-475 -1600);
FORCEPROP 2 LAST CDS_LOCATION C158
J 0
(-475 -1600);
DISPLAY 1.021277 (-475 -1600);
DISPLAY INVISIBLE (-475 -1600);
FORCEPROP 2 LAST $SEC 1
J 2
(-550 -1600);
DISPLAY 0.680851 (-550 -1600);
PAINT MONO (-550 -1600);
DISPLAY INVISIBLE (-550 -1600);
FORCEPROP 2 LAST CDS_SEC 1
J 2
(-550 -1600);
DISPLAY 0.680851 (-550 -1600);
DISPLAY INVISIBLE (-550 -1600);
FORCEADD Q_CAP_DIFFBUS..2
R 2
(-725 -1825);
FORCEPROP 1 LAST PART_NUMBER SP_CH4221MEE01
J 2
(-841 -1737);
DISPLAY 0.574468 (-841 -1737);
PAINT GREEN (-841 -1737);
DISPLAY INVISIBLE (-841 -1737);
FORCEPROP 2 LAST VALUE DIFF BUS_0.22UF
J 2
(-875 -1825);
DISPLAY 0.553191 (-875 -1825);
FORCEPROP 1 LAST $LOCATION C159
J 2
(-491 -1808);
DISPLAY 0.723404 (-491 -1808);
PAINT GREEN (-491 -1808);
FORCEPROP 2 LASTPIN (-650 -1825) $PN 1
J 0
(-640 -1815);
DISPLAY 0.808511 (-640 -1815);
FORCEPROP 2 LASTPIN (-800 -1825) $PN 2
J 2
(-810 -1815);
DISPLAY 0.808511 (-810 -1815);
FORCEPROP 2 LAST TOLERANCE 20%
J 2
(-800 -1775);
DISPLAY 0.553191 (-800 -1775);
DISPLAY INVISIBLE (-800 -1775);
FORCEPROP 2 LAST PACK_TYPE C0201
J 2
(-900 -1775);
DISPLAY 0.553191 (-900 -1775);
DISPLAY INVISIBLE (-900 -1775);
FORCEPROP 1 LAST MATERIAL X6S
J 2
(-716 -1746);
DISPLAY 0.574468 (-716 -1746);
PAINT GREEN (-716 -1746);
DISPLAY INVISIBLE (-716 -1746);
FORCEPROP 2 LAST VOLTAGE 6.3V
J 2
(-1075 -1775);
DISPLAY 0.553191 (-1075 -1775);
DISPLAY INVISIBLE (-1075 -1775);
FORCEPROP 1 LAST CDS_LMAN_SYM_OUTLINE -25,50,25,-50
J 2
(-725 -1825);
DISPLAY 0.468085 (-725 -1825);
PAINT GREEN (-725 -1825);
DISPLAY INVISIBLE (-725 -1825);
FORCEPROP 2 LAST CDS_LIB pure_quanta
J 2
(-725 -1825);
DISPLAY INVISIBLE (-725 -1825);
FORCEPROP 1 LAST PIN_NAMES_ROTATE TRUE
J 2
(-725 -1825);
DISPLAY 0.489362 (-725 -1825);
PAINT GREEN (-725 -1825);
DISPLAY INVISIBLE (-725 -1825);
FORCEPROP 1 LAST PATH I117
J 2
(-725 -1825);
DISPLAY 0.723404 (-725 -1825);
DISPLAY INVISIBLE (-725 -1825);
FORCEPROP 1 LAST $LOCATION C159
J 0
(-475 -1750);
DISPLAY 1.021277 (-475 -1750);
DISPLAY INVISIBLE (-475 -1750);
FORCEPROP 2 LAST CDS_LOCATION C159
J 0
(-475 -1750);
DISPLAY 1.021277 (-475 -1750);
DISPLAY INVISIBLE (-475 -1750);
FORCEPROP 2 LAST $SEC 1
J 2
(-550 -1750);
DISPLAY 0.680851 (-550 -1750);
PAINT MONO (-550 -1750);
DISPLAY INVISIBLE (-550 -1750);
FORCEPROP 2 LAST CDS_SEC 1
J 2
(-550 -1750);
DISPLAY 0.680851 (-550 -1750);
DISPLAY INVISIBLE (-550 -1750);
FORCEADD Q_CAP_DIFFBUS..2
R 2
(-725 -1875);
FORCEPROP 1 LAST PART_NUMBER SP_CH4221MEE01
J 2
(-841 -1787);
DISPLAY 0.574468 (-841 -1787);
PAINT GREEN (-841 -1787);
DISPLAY INVISIBLE (-841 -1787);
FORCEPROP 2 LAST VALUE DIFF BUS_0.22UF
J 2
(-875 -1875);
DISPLAY 0.553191 (-875 -1875);
FORCEPROP 1 LAST $LOCATION C160
J 2
(-491 -1858);
DISPLAY 0.723404 (-491 -1858);
PAINT GREEN (-491 -1858);
FORCEPROP 2 LASTPIN (-650 -1875) $PN 1
J 0
(-640 -1865);
DISPLAY 0.808511 (-640 -1865);
FORCEPROP 2 LASTPIN (-800 -1875) $PN 2
J 2
(-810 -1865);
DISPLAY 0.808511 (-810 -1865);
FORCEPROP 2 LAST TOLERANCE 20%
J 2
(-800 -1825);
DISPLAY 0.553191 (-800 -1825);
DISPLAY INVISIBLE (-800 -1825);
FORCEPROP 2 LAST PACK_TYPE C0201
J 2
(-900 -1825);
DISPLAY 0.553191 (-900 -1825);
DISPLAY INVISIBLE (-900 -1825);
FORCEPROP 1 LAST MATERIAL X6S
J 2
(-716 -1796);
DISPLAY 0.574468 (-716 -1796);
PAINT GREEN (-716 -1796);
DISPLAY INVISIBLE (-716 -1796);
FORCEPROP 2 LAST VOLTAGE 6.3V
J 2
(-1075 -1825);
DISPLAY 0.553191 (-1075 -1825);
DISPLAY INVISIBLE (-1075 -1825);
FORCEPROP 1 LAST CDS_LMAN_SYM_OUTLINE -25,50,25,-50
J 2
(-725 -1875);
DISPLAY 0.468085 (-725 -1875);
PAINT GREEN (-725 -1875);
DISPLAY INVISIBLE (-725 -1875);
FORCEPROP 2 LAST CDS_LIB pure_quanta
J 2
(-725 -1875);
DISPLAY INVISIBLE (-725 -1875);
FORCEPROP 1 LAST PIN_NAMES_ROTATE TRUE
J 2
(-725 -1875);
DISPLAY 0.489362 (-725 -1875);
PAINT GREEN (-725 -1875);
DISPLAY INVISIBLE (-725 -1875);
FORCEPROP 1 LAST PATH I118
J 2
(-725 -1875);
DISPLAY 0.723404 (-725 -1875);
DISPLAY INVISIBLE (-725 -1875);
FORCEPROP 1 LAST $LOCATION C160
J 0
(-475 -1800);
DISPLAY 1.021277 (-475 -1800);
DISPLAY INVISIBLE (-475 -1800);
FORCEPROP 2 LAST CDS_LOCATION C160
J 0
(-475 -1800);
DISPLAY 1.021277 (-475 -1800);
DISPLAY INVISIBLE (-475 -1800);
FORCEPROP 2 LAST $SEC 1
J 2
(-550 -1800);
DISPLAY 0.680851 (-550 -1800);
PAINT MONO (-550 -1800);
DISPLAY INVISIBLE (-550 -1800);
FORCEPROP 2 LAST CDS_SEC 1
J 2
(-550 -1800);
DISPLAY 0.680851 (-550 -1800);
DISPLAY INVISIBLE (-550 -1800);
FORCEADD Q_CAP_DIFFBUS..2
R 2
(-725 -2025);
FORCEPROP 1 LAST PART_NUMBER SP_CH4221MEE01
J 2
(-841 -1937);
DISPLAY 0.574468 (-841 -1937);
PAINT GREEN (-841 -1937);
DISPLAY INVISIBLE (-841 -1937);
FORCEPROP 2 LAST VALUE DIFF BUS_0.22UF
J 2
(-875 -2025);
DISPLAY 0.553191 (-875 -2025);
FORCEPROP 1 LAST $LOCATION C161
J 2
(-491 -2008);
DISPLAY 0.723404 (-491 -2008);
PAINT GREEN (-491 -2008);
FORCEPROP 2 LASTPIN (-650 -2025) $PN 1
J 0
(-640 -2015);
DISPLAY 0.808511 (-640 -2015);
FORCEPROP 2 LASTPIN (-800 -2025) $PN 2
J 2
(-810 -2015);
DISPLAY 0.808511 (-810 -2015);
FORCEPROP 2 LAST TOLERANCE 20%
J 2
(-800 -1975);
DISPLAY 0.553191 (-800 -1975);
DISPLAY INVISIBLE (-800 -1975);
FORCEPROP 2 LAST PACK_TYPE C0201
J 2
(-900 -1975);
DISPLAY 0.553191 (-900 -1975);
DISPLAY INVISIBLE (-900 -1975);
FORCEPROP 1 LAST MATERIAL X6S
J 2
(-716 -1946);
DISPLAY 0.574468 (-716 -1946);
PAINT GREEN (-716 -1946);
DISPLAY INVISIBLE (-716 -1946);
FORCEPROP 2 LAST VOLTAGE 6.3V
J 2
(-1075 -1975);
DISPLAY 0.553191 (-1075 -1975);
DISPLAY INVISIBLE (-1075 -1975);
FORCEPROP 1 LAST CDS_LMAN_SYM_OUTLINE -25,50,25,-50
J 2
(-725 -2025);
DISPLAY 0.468085 (-725 -2025);
PAINT GREEN (-725 -2025);
DISPLAY INVISIBLE (-725 -2025);
FORCEPROP 2 LAST CDS_LIB pure_quanta
J 2
(-725 -2025);
DISPLAY INVISIBLE (-725 -2025);
FORCEPROP 1 LAST PIN_NAMES_ROTATE TRUE
J 2
(-725 -2025);
DISPLAY 0.489362 (-725 -2025);
PAINT GREEN (-725 -2025);
DISPLAY INVISIBLE (-725 -2025);
FORCEPROP 1 LAST PATH I119
J 2
(-725 -2025);
DISPLAY 0.723404 (-725 -2025);
DISPLAY INVISIBLE (-725 -2025);
FORCEPROP 1 LAST $LOCATION C161
J 0
(-475 -1950);
DISPLAY 1.021277 (-475 -1950);
DISPLAY INVISIBLE (-475 -1950);
FORCEPROP 2 LAST CDS_LOCATION C161
J 0
(-475 -1950);
DISPLAY 1.021277 (-475 -1950);
DISPLAY INVISIBLE (-475 -1950);
FORCEPROP 2 LAST $SEC 1
J 2
(-550 -1950);
DISPLAY 0.680851 (-550 -1950);
PAINT MONO (-550 -1950);
DISPLAY INVISIBLE (-550 -1950);
FORCEPROP 2 LAST CDS_SEC 1
J 2
(-550 -1950);
DISPLAY 0.680851 (-550 -1950);
DISPLAY INVISIBLE (-550 -1950);
FORCEADD TAP..1
R 2
(-1450 575);
FORCEPROP 3 LASTPIN (-1400 575) SIG_NAME DMI_CPU0_PCH_TX_DN<2>
J 0
(-1390 585);
DISPLAY 0.659574 (-1390 585);
PAINT MONO (-1390 585);
DISPLAY INVISIBLE (-1390 585);
FORCEPROP 1 LASTPIN (-1400 575) BN 2
J 2
(-1388 583);
DISPLAY 0.680851 (-1388 583);
PAINT GREEN (-1388 583);
FORCEPROP 2 LAST CDS_LIB standard
J 0
(-1450 575);
DISPLAY INVISIBLE (-1450 575);
FORCEPROP 1 LAST BODY_TYPE PLUMBING
J 2
(-1450 625);
DISPLAY 0.872340 (-1450 625);
PAINT GREEN (-1450 625);
DISPLAY INVISIBLE (-1450 625);
FORCEPROP 1 LAST HDL_TAP TRUE
J 2
(-1775 450);
DISPLAY 0.872340 (-1775 450);
DISPLAY INVISIBLE (-1775 450);
FORCEPROP 1 LAST PATH I12
J 2
(-1448 575);
DISPLAY 0.872340 (-1448 575);
PAINT GREEN (-1448 575);
DISPLAY INVISIBLE (-1448 575);
FORCEADD Q_CAP_DIFFBUS..2
R 2
(-725 -2075);
FORCEPROP 1 LAST PART_NUMBER SP_CH4221MEE01
J 2
(-841 -1987);
DISPLAY 0.574468 (-841 -1987);
PAINT GREEN (-841 -1987);
DISPLAY INVISIBLE (-841 -1987);
FORCEPROP 2 LAST VALUE DIFF BUS_0.22UF
J 2
(-875 -2075);
DISPLAY 0.553191 (-875 -2075);
FORCEPROP 1 LAST $LOCATION C162
J 2
(-491 -2058);
DISPLAY 0.723404 (-491 -2058);
PAINT GREEN (-491 -2058);
FORCEPROP 2 LASTPIN (-650 -2075) $PN 1
J 0
(-640 -2065);
DISPLAY 0.808511 (-640 -2065);
FORCEPROP 2 LASTPIN (-800 -2075) $PN 2
J 2
(-810 -2065);
DISPLAY 0.808511 (-810 -2065);
FORCEPROP 2 LAST TOLERANCE 20%
J 2
(-800 -2025);
DISPLAY 0.553191 (-800 -2025);
DISPLAY INVISIBLE (-800 -2025);
FORCEPROP 2 LAST PACK_TYPE C0201
J 2
(-900 -2025);
DISPLAY 0.553191 (-900 -2025);
DISPLAY INVISIBLE (-900 -2025);
FORCEPROP 1 LAST MATERIAL X6S
J 2
(-716 -1996);
DISPLAY 0.574468 (-716 -1996);
PAINT GREEN (-716 -1996);
DISPLAY INVISIBLE (-716 -1996);
FORCEPROP 2 LAST VOLTAGE 6.3V
J 2
(-1075 -2025);
DISPLAY 0.553191 (-1075 -2025);
DISPLAY INVISIBLE (-1075 -2025);
FORCEPROP 1 LAST CDS_LMAN_SYM_OUTLINE -25,50,25,-50
J 2
(-725 -2075);
DISPLAY 0.468085 (-725 -2075);
PAINT GREEN (-725 -2075);
DISPLAY INVISIBLE (-725 -2075);
FORCEPROP 2 LAST CDS_LIB pure_quanta
J 2
(-725 -2075);
DISPLAY INVISIBLE (-725 -2075);
FORCEPROP 1 LAST PIN_NAMES_ROTATE TRUE
J 2
(-725 -2075);
DISPLAY 0.489362 (-725 -2075);
PAINT GREEN (-725 -2075);
DISPLAY INVISIBLE (-725 -2075);
FORCEPROP 1 LAST PATH I120
J 2
(-725 -2075);
DISPLAY 0.723404 (-725 -2075);
DISPLAY INVISIBLE (-725 -2075);
FORCEPROP 1 LAST $LOCATION C162
J 0
(-475 -2000);
DISPLAY 1.021277 (-475 -2000);
DISPLAY INVISIBLE (-475 -2000);
FORCEPROP 2 LAST CDS_LOCATION C162
J 0
(-475 -2000);
DISPLAY 1.021277 (-475 -2000);
DISPLAY INVISIBLE (-475 -2000);
FORCEPROP 2 LAST $SEC 1
J 2
(-550 -2000);
DISPLAY 0.680851 (-550 -2000);
PAINT MONO (-550 -2000);
DISPLAY INVISIBLE (-550 -2000);
FORCEPROP 2 LAST CDS_SEC 1
J 2
(-550 -2000);
DISPLAY 0.680851 (-550 -2000);
DISPLAY INVISIBLE (-550 -2000);
FORCEADD Q_CAP_DIFFBUS..2
R 2
(-725 -2225);
FORCEPROP 1 LAST PART_NUMBER SP_CH4221MEE01
J 2
(-841 -2137);
DISPLAY 0.574468 (-841 -2137);
PAINT GREEN (-841 -2137);
DISPLAY INVISIBLE (-841 -2137);
FORCEPROP 2 LAST VALUE DIFF BUS_0.22UF
J 2
(-875 -2225);
DISPLAY 0.553191 (-875 -2225);
FORCEPROP 1 LAST $LOCATION C163
J 2
(-491 -2208);
DISPLAY 0.723404 (-491 -2208);
PAINT GREEN (-491 -2208);
FORCEPROP 2 LASTPIN (-650 -2225) $PN 1
J 0
(-640 -2215);
DISPLAY 0.808511 (-640 -2215);
FORCEPROP 2 LASTPIN (-800 -2225) $PN 2
J 2
(-810 -2215);
DISPLAY 0.808511 (-810 -2215);
FORCEPROP 2 LAST TOLERANCE 20%
J 2
(-800 -2175);
DISPLAY 0.553191 (-800 -2175);
DISPLAY INVISIBLE (-800 -2175);
FORCEPROP 2 LAST PACK_TYPE C0201
J 2
(-900 -2175);
DISPLAY 0.553191 (-900 -2175);
DISPLAY INVISIBLE (-900 -2175);
FORCEPROP 1 LAST MATERIAL X6S
J 2
(-716 -2146);
DISPLAY 0.574468 (-716 -2146);
PAINT GREEN (-716 -2146);
DISPLAY INVISIBLE (-716 -2146);
FORCEPROP 2 LAST VOLTAGE 6.3V
J 2
(-1075 -2175);
DISPLAY 0.553191 (-1075 -2175);
DISPLAY INVISIBLE (-1075 -2175);
FORCEPROP 2 LAST CDS_LIB pure_quanta
J 2
(-725 -2225);
DISPLAY INVISIBLE (-725 -2225);
FORCEPROP 1 LAST CDS_LMAN_SYM_OUTLINE -25,50,25,-50
J 2
(-725 -2225);
DISPLAY 0.468085 (-725 -2225);
PAINT GREEN (-725 -2225);
DISPLAY INVISIBLE (-725 -2225);
FORCEPROP 1 LAST PIN_NAMES_ROTATE TRUE
J 2
(-725 -2225);
DISPLAY 0.489362 (-725 -2225);
PAINT GREEN (-725 -2225);
DISPLAY INVISIBLE (-725 -2225);
FORCEPROP 1 LAST PATH I121
J 2
(-725 -2225);
DISPLAY 0.723404 (-725 -2225);
DISPLAY INVISIBLE (-725 -2225);
FORCEPROP 1 LAST $LOCATION C163
J 0
(-475 -2150);
DISPLAY 1.021277 (-475 -2150);
DISPLAY INVISIBLE (-475 -2150);
FORCEPROP 2 LAST CDS_LOCATION C163
J 0
(-475 -2150);
DISPLAY 1.021277 (-475 -2150);
DISPLAY INVISIBLE (-475 -2150);
FORCEPROP 2 LAST $SEC 1
J 2
(-550 -2150);
DISPLAY 0.680851 (-550 -2150);
PAINT MONO (-550 -2150);
DISPLAY INVISIBLE (-550 -2150);
FORCEPROP 2 LAST CDS_SEC 1
J 2
(-550 -2150);
DISPLAY 0.680851 (-550 -2150);
DISPLAY INVISIBLE (-550 -2150);
FORCEADD Q_CAP_DIFFBUS..2
R 2
(-725 -2275);
FORCEPROP 1 LAST PART_NUMBER SP_CH4221MEE01
J 2
(-841 -2187);
DISPLAY 0.574468 (-841 -2187);
PAINT GREEN (-841 -2187);
DISPLAY INVISIBLE (-841 -2187);
FORCEPROP 2 LAST VALUE DIFF BUS_0.22UF
J 2
(-875 -2275);
DISPLAY 0.553191 (-875 -2275);
FORCEPROP 1 LAST $LOCATION C164
J 2
(-491 -2258);
DISPLAY 0.723404 (-491 -2258);
PAINT GREEN (-491 -2258);
FORCEPROP 2 LASTPIN (-650 -2275) $PN 1
J 0
(-640 -2265);
DISPLAY 0.808511 (-640 -2265);
FORCEPROP 2 LASTPIN (-800 -2275) $PN 2
J 2
(-810 -2265);
DISPLAY 0.808511 (-810 -2265);
FORCEPROP 2 LAST TOLERANCE 20%
J 2
(-800 -2225);
DISPLAY 0.553191 (-800 -2225);
DISPLAY INVISIBLE (-800 -2225);
FORCEPROP 2 LAST PACK_TYPE C0201
J 2
(-900 -2225);
DISPLAY 0.553191 (-900 -2225);
DISPLAY INVISIBLE (-900 -2225);
FORCEPROP 1 LAST MATERIAL X6S
J 2
(-716 -2196);
DISPLAY 0.574468 (-716 -2196);
PAINT GREEN (-716 -2196);
DISPLAY INVISIBLE (-716 -2196);
FORCEPROP 2 LAST VOLTAGE 6.3V
J 2
(-1075 -2225);
DISPLAY 0.553191 (-1075 -2225);
DISPLAY INVISIBLE (-1075 -2225);
FORCEPROP 2 LAST CDS_LIB pure_quanta
J 2
(-725 -2275);
DISPLAY INVISIBLE (-725 -2275);
FORCEPROP 1 LAST CDS_LMAN_SYM_OUTLINE -25,50,25,-50
J 2
(-725 -2275);
DISPLAY 0.468085 (-725 -2275);
PAINT GREEN (-725 -2275);
DISPLAY INVISIBLE (-725 -2275);
FORCEPROP 1 LAST PIN_NAMES_ROTATE TRUE
J 2
(-725 -2275);
DISPLAY 0.489362 (-725 -2275);
PAINT GREEN (-725 -2275);
DISPLAY INVISIBLE (-725 -2275);
FORCEPROP 1 LAST PATH I122
J 2
(-725 -2275);
DISPLAY 0.723404 (-725 -2275);
DISPLAY INVISIBLE (-725 -2275);
FORCEPROP 1 LAST $LOCATION C164
J 0
(-475 -2200);
DISPLAY 1.021277 (-475 -2200);
DISPLAY INVISIBLE (-475 -2200);
FORCEPROP 2 LAST CDS_LOCATION C164
J 0
(-475 -2200);
DISPLAY 1.021277 (-475 -2200);
DISPLAY INVISIBLE (-475 -2200);
FORCEPROP 2 LAST $SEC 1
J 2
(-550 -2200);
DISPLAY 0.680851 (-550 -2200);
PAINT MONO (-550 -2200);
DISPLAY INVISIBLE (-550 -2200);
FORCEPROP 2 LAST CDS_SEC 1
J 2
(-550 -2200);
DISPLAY 0.680851 (-550 -2200);
DISPLAY INVISIBLE (-550 -2200);
FORCEADD Q_CAP_DIFFBUS..2
R 2
(-725 -2425);
FORCEPROP 1 LAST PART_NUMBER SP_CH4221MEE01
J 2
(-841 -2337);
DISPLAY 0.574468 (-841 -2337);
PAINT GREEN (-841 -2337);
DISPLAY INVISIBLE (-841 -2337);
FORCEPROP 2 LAST VALUE DIFF BUS_0.22UF
J 2
(-875 -2425);
DISPLAY 0.553191 (-875 -2425);
FORCEPROP 1 LAST $LOCATION C165
J 2
(-491 -2408);
DISPLAY 0.723404 (-491 -2408);
PAINT GREEN (-491 -2408);
FORCEPROP 2 LASTPIN (-650 -2425) $PN 1
J 0
(-640 -2415);
DISPLAY 0.808511 (-640 -2415);
FORCEPROP 2 LASTPIN (-800 -2425) $PN 2
J 2
(-810 -2415);
DISPLAY 0.808511 (-810 -2415);
FORCEPROP 2 LAST TOLERANCE 20%
J 2
(-800 -2375);
DISPLAY 0.553191 (-800 -2375);
DISPLAY INVISIBLE (-800 -2375);
FORCEPROP 2 LAST PACK_TYPE C0201
J 2
(-900 -2375);
DISPLAY 0.553191 (-900 -2375);
DISPLAY INVISIBLE (-900 -2375);
FORCEPROP 1 LAST MATERIAL X6S
J 2
(-716 -2346);
DISPLAY 0.574468 (-716 -2346);
PAINT GREEN (-716 -2346);
DISPLAY INVISIBLE (-716 -2346);
FORCEPROP 2 LAST VOLTAGE 6.3V
J 2
(-1075 -2375);
DISPLAY 0.553191 (-1075 -2375);
DISPLAY INVISIBLE (-1075 -2375);
FORCEPROP 1 LAST CDS_LMAN_SYM_OUTLINE -25,50,25,-50
J 2
(-725 -2425);
DISPLAY 0.468085 (-725 -2425);
PAINT GREEN (-725 -2425);
DISPLAY INVISIBLE (-725 -2425);
FORCEPROP 2 LAST CDS_LIB pure_quanta
J 2
(-725 -2425);
DISPLAY INVISIBLE (-725 -2425);
FORCEPROP 1 LAST PIN_NAMES_ROTATE TRUE
J 2
(-725 -2425);
DISPLAY 0.489362 (-725 -2425);
PAINT GREEN (-725 -2425);
DISPLAY INVISIBLE (-725 -2425);
FORCEPROP 1 LAST PATH I123
J 2
(-725 -2425);
DISPLAY 0.723404 (-725 -2425);
DISPLAY INVISIBLE (-725 -2425);
FORCEPROP 1 LAST $LOCATION C165
J 0
(-475 -2350);
DISPLAY 1.021277 (-475 -2350);
DISPLAY INVISIBLE (-475 -2350);
FORCEPROP 2 LAST CDS_LOCATION C165
J 0
(-475 -2350);
DISPLAY 1.021277 (-475 -2350);
DISPLAY INVISIBLE (-475 -2350);
FORCEPROP 2 LAST $SEC 1
J 2
(-550 -2350);
DISPLAY 0.680851 (-550 -2350);
PAINT MONO (-550 -2350);
DISPLAY INVISIBLE (-550 -2350);
FORCEPROP 2 LAST CDS_SEC 1
J 2
(-550 -2350);
DISPLAY 0.680851 (-550 -2350);
DISPLAY INVISIBLE (-550 -2350);
FORCEADD Q_CAP_DIFFBUS..2
R 2
(-725 -2475);
FORCEPROP 1 LAST PART_NUMBER SP_CH4221MEE01
J 2
(-841 -2387);
DISPLAY 0.574468 (-841 -2387);
PAINT GREEN (-841 -2387);
DISPLAY INVISIBLE (-841 -2387);
FORCEPROP 2 LAST VALUE DIFF BUS_0.22UF
J 2
(-875 -2475);
DISPLAY 0.553191 (-875 -2475);
FORCEPROP 1 LAST $LOCATION C166
J 2
(-491 -2458);
DISPLAY 0.723404 (-491 -2458);
PAINT GREEN (-491 -2458);
FORCEPROP 2 LASTPIN (-650 -2475) $PN 1
J 0
(-640 -2465);
DISPLAY 0.808511 (-640 -2465);
FORCEPROP 2 LASTPIN (-800 -2475) $PN 2
J 2
(-810 -2465);
DISPLAY 0.808511 (-810 -2465);
FORCEPROP 2 LAST TOLERANCE 20%
J 2
(-800 -2425);
DISPLAY 0.553191 (-800 -2425);
DISPLAY INVISIBLE (-800 -2425);
FORCEPROP 2 LAST PACK_TYPE C0201
J 2
(-900 -2425);
DISPLAY 0.553191 (-900 -2425);
DISPLAY INVISIBLE (-900 -2425);
FORCEPROP 1 LAST MATERIAL X6S
J 2
(-716 -2396);
DISPLAY 0.574468 (-716 -2396);
PAINT GREEN (-716 -2396);
DISPLAY INVISIBLE (-716 -2396);
FORCEPROP 2 LAST VOLTAGE 6.3V
J 2
(-1075 -2425);
DISPLAY 0.553191 (-1075 -2425);
DISPLAY INVISIBLE (-1075 -2425);
FORCEPROP 1 LAST CDS_LMAN_SYM_OUTLINE -25,50,25,-50
J 2
(-725 -2475);
DISPLAY 0.468085 (-725 -2475);
PAINT GREEN (-725 -2475);
DISPLAY INVISIBLE (-725 -2475);
FORCEPROP 2 LAST CDS_LIB pure_quanta
J 2
(-725 -2475);
DISPLAY INVISIBLE (-725 -2475);
FORCEPROP 1 LAST PIN_NAMES_ROTATE TRUE
J 2
(-725 -2475);
DISPLAY 0.489362 (-725 -2475);
PAINT GREEN (-725 -2475);
DISPLAY INVISIBLE (-725 -2475);
FORCEPROP 1 LAST PATH I124
J 2
(-725 -2475);
DISPLAY 0.723404 (-725 -2475);
DISPLAY INVISIBLE (-725 -2475);
FORCEPROP 1 LAST $LOCATION C166
J 0
(-475 -2400);
DISPLAY 1.021277 (-475 -2400);
DISPLAY INVISIBLE (-475 -2400);
FORCEPROP 2 LAST CDS_LOCATION C166
J 0
(-475 -2400);
DISPLAY 1.021277 (-475 -2400);
DISPLAY INVISIBLE (-475 -2400);
FORCEPROP 2 LAST $SEC 1
J 2
(-550 -2400);
DISPLAY 0.680851 (-550 -2400);
PAINT MONO (-550 -2400);
DISPLAY INVISIBLE (-550 -2400);
FORCEPROP 2 LAST CDS_SEC 1
J 2
(-550 -2400);
DISPLAY 0.680851 (-550 -2400);
DISPLAY INVISIBLE (-550 -2400);
FORCEADD Q_CAP_DIFFBUS..2
R 2
(-725 -2675);
FORCEPROP 1 LAST PART_NUMBER SP_CH4221MEE01
J 2
(-841 -2587);
DISPLAY 0.574468 (-841 -2587);
PAINT GREEN (-841 -2587);
DISPLAY INVISIBLE (-841 -2587);
FORCEPROP 2 LAST VALUE DIFF BUS_0.22UF
J 2
(-875 -2675);
DISPLAY 0.553191 (-875 -2675);
FORCEPROP 1 LAST $LOCATION C168
J 2
(-491 -2658);
DISPLAY 0.723404 (-491 -2658);
PAINT GREEN (-491 -2658);
FORCEPROP 2 LASTPIN (-650 -2675) $PN 1
J 0
(-640 -2665);
DISPLAY 0.808511 (-640 -2665);
FORCEPROP 2 LASTPIN (-800 -2675) $PN 2
J 2
(-810 -2665);
DISPLAY 0.808511 (-810 -2665);
FORCEPROP 2 LAST TOLERANCE 20%
J 2
(-800 -2625);
DISPLAY 0.553191 (-800 -2625);
DISPLAY INVISIBLE (-800 -2625);
FORCEPROP 2 LAST PACK_TYPE C0201
J 2
(-900 -2625);
DISPLAY 0.553191 (-900 -2625);
DISPLAY INVISIBLE (-900 -2625);
FORCEPROP 1 LAST MATERIAL X6S
J 2
(-716 -2596);
DISPLAY 0.574468 (-716 -2596);
PAINT GREEN (-716 -2596);
DISPLAY INVISIBLE (-716 -2596);
FORCEPROP 2 LAST VOLTAGE 6.3V
J 2
(-1075 -2625);
DISPLAY 0.553191 (-1075 -2625);
DISPLAY INVISIBLE (-1075 -2625);
FORCEPROP 1 LAST CDS_LMAN_SYM_OUTLINE -25,50,25,-50
J 2
(-725 -2675);
DISPLAY 0.468085 (-725 -2675);
PAINT GREEN (-725 -2675);
DISPLAY INVISIBLE (-725 -2675);
FORCEPROP 2 LAST CDS_LIB pure_quanta
J 2
(-725 -2675);
DISPLAY INVISIBLE (-725 -2675);
FORCEPROP 1 LAST PIN_NAMES_ROTATE TRUE
J 2
(-725 -2675);
DISPLAY 0.489362 (-725 -2675);
PAINT GREEN (-725 -2675);
DISPLAY INVISIBLE (-725 -2675);
FORCEPROP 1 LAST PATH I125
J 2
(-725 -2675);
DISPLAY 0.723404 (-725 -2675);
DISPLAY INVISIBLE (-725 -2675);
FORCEPROP 1 LAST $LOCATION C168
J 0
(-475 -2600);
DISPLAY 1.021277 (-475 -2600);
DISPLAY INVISIBLE (-475 -2600);
FORCEPROP 2 LAST CDS_LOCATION C168
J 0
(-475 -2600);
DISPLAY 1.021277 (-475 -2600);
DISPLAY INVISIBLE (-475 -2600);
FORCEPROP 2 LAST $SEC 1
J 2
(-550 -2600);
DISPLAY 0.680851 (-550 -2600);
PAINT MONO (-550 -2600);
DISPLAY INVISIBLE (-550 -2600);
FORCEPROP 2 LAST CDS_SEC 1
J 2
(-550 -2600);
DISPLAY 0.680851 (-550 -2600);
DISPLAY INVISIBLE (-550 -2600);
FORCEADD Q_CAP_DIFFBUS..2
R 2
(-725 -2625);
FORCEPROP 1 LAST PART_NUMBER SP_CH4221MEE01
J 2
(-841 -2537);
DISPLAY 0.574468 (-841 -2537);
PAINT GREEN (-841 -2537);
DISPLAY INVISIBLE (-841 -2537);
FORCEPROP 2 LAST VALUE DIFF BUS_0.22UF
J 2
(-875 -2625);
DISPLAY 0.553191 (-875 -2625);
FORCEPROP 1 LAST $LOCATION C167
J 2
(-491 -2608);
DISPLAY 0.723404 (-491 -2608);
PAINT GREEN (-491 -2608);
FORCEPROP 2 LASTPIN (-650 -2625) $PN 1
J 0
(-640 -2615);
DISPLAY 0.808511 (-640 -2615);
FORCEPROP 2 LASTPIN (-800 -2625) $PN 2
J 2
(-810 -2615);
DISPLAY 0.808511 (-810 -2615);
FORCEPROP 2 LAST TOLERANCE 20%
J 2
(-800 -2575);
DISPLAY 0.553191 (-800 -2575);
DISPLAY INVISIBLE (-800 -2575);
FORCEPROP 2 LAST PACK_TYPE C0201
J 2
(-900 -2575);
DISPLAY 0.553191 (-900 -2575);
DISPLAY INVISIBLE (-900 -2575);
FORCEPROP 1 LAST MATERIAL X6S
J 2
(-716 -2546);
DISPLAY 0.574468 (-716 -2546);
PAINT GREEN (-716 -2546);
DISPLAY INVISIBLE (-716 -2546);
FORCEPROP 2 LAST VOLTAGE 6.3V
J 2
(-1075 -2575);
DISPLAY 0.553191 (-1075 -2575);
DISPLAY INVISIBLE (-1075 -2575);
FORCEPROP 2 LAST CDS_LIB pure_quanta
J 2
(-725 -2625);
DISPLAY INVISIBLE (-725 -2625);
FORCEPROP 1 LAST CDS_LMAN_SYM_OUTLINE -25,50,25,-50
J 2
(-725 -2625);
DISPLAY 0.468085 (-725 -2625);
PAINT GREEN (-725 -2625);
DISPLAY INVISIBLE (-725 -2625);
FORCEPROP 1 LAST PIN_NAMES_ROTATE TRUE
J 2
(-725 -2625);
DISPLAY 0.489362 (-725 -2625);
PAINT GREEN (-725 -2625);
DISPLAY INVISIBLE (-725 -2625);
FORCEPROP 1 LAST PATH I126
J 2
(-725 -2625);
DISPLAY 0.723404 (-725 -2625);
DISPLAY INVISIBLE (-725 -2625);
FORCEPROP 1 LAST $LOCATION C167
J 0
(-475 -2550);
DISPLAY 1.021277 (-475 -2550);
DISPLAY INVISIBLE (-475 -2550);
FORCEPROP 2 LAST CDS_LOCATION C167
J 0
(-475 -2550);
DISPLAY 1.021277 (-475 -2550);
DISPLAY INVISIBLE (-475 -2550);
FORCEPROP 2 LAST $SEC 1
J 2
(-550 -2550);
DISPLAY 0.680851 (-550 -2550);
PAINT MONO (-550 -2550);
DISPLAY INVISIBLE (-550 -2550);
FORCEPROP 2 LAST CDS_SEC 1
J 2
(-550 -2550);
DISPLAY 0.680851 (-550 -2550);
DISPLAY INVISIBLE (-550 -2550);
FORCEADD Q_CAP_DIFFBUS..2
R 2
(-725 -2825);
FORCEPROP 1 LAST PART_NUMBER SP_CH4221MEE01
J 2
(-841 -2737);
DISPLAY 0.574468 (-841 -2737);
PAINT GREEN (-841 -2737);
DISPLAY INVISIBLE (-841 -2737);
FORCEPROP 2 LAST VALUE DIFF BUS_0.22UF
J 2
(-875 -2825);
DISPLAY 0.553191 (-875 -2825);
FORCEPROP 1 LAST $LOCATION C169
J 2
(-491 -2808);
DISPLAY 0.723404 (-491 -2808);
PAINT GREEN (-491 -2808);
FORCEPROP 2 LASTPIN (-650 -2825) $PN 1
J 0
(-640 -2815);
DISPLAY 0.808511 (-640 -2815);
FORCEPROP 2 LASTPIN (-800 -2825) $PN 2
J 2
(-810 -2815);
DISPLAY 0.808511 (-810 -2815);
FORCEPROP 2 LAST TOLERANCE 20%
J 2
(-800 -2775);
DISPLAY 0.553191 (-800 -2775);
DISPLAY INVISIBLE (-800 -2775);
FORCEPROP 2 LAST PACK_TYPE C0201
J 2
(-900 -2775);
DISPLAY 0.553191 (-900 -2775);
DISPLAY INVISIBLE (-900 -2775);
FORCEPROP 1 LAST MATERIAL X6S
J 2
(-716 -2746);
DISPLAY 0.574468 (-716 -2746);
PAINT GREEN (-716 -2746);
DISPLAY INVISIBLE (-716 -2746);
FORCEPROP 2 LAST VOLTAGE 6.3V
J 2
(-1075 -2775);
DISPLAY 0.553191 (-1075 -2775);
DISPLAY INVISIBLE (-1075 -2775);
FORCEPROP 1 LAST CDS_LMAN_SYM_OUTLINE -25,50,25,-50
J 2
(-725 -2825);
DISPLAY 0.468085 (-725 -2825);
PAINT GREEN (-725 -2825);
DISPLAY INVISIBLE (-725 -2825);
FORCEPROP 2 LAST CDS_LIB pure_quanta
J 2
(-725 -2825);
DISPLAY INVISIBLE (-725 -2825);
FORCEPROP 1 LAST PIN_NAMES_ROTATE TRUE
J 2
(-725 -2825);
DISPLAY 0.489362 (-725 -2825);
PAINT GREEN (-725 -2825);
DISPLAY INVISIBLE (-725 -2825);
FORCEPROP 1 LAST PATH I127
J 2
(-725 -2825);
DISPLAY 0.723404 (-725 -2825);
DISPLAY INVISIBLE (-725 -2825);
FORCEPROP 1 LAST $LOCATION C169
J 0
(-475 -2750);
DISPLAY 1.021277 (-475 -2750);
DISPLAY INVISIBLE (-475 -2750);
FORCEPROP 2 LAST CDS_LOCATION C169
J 0
(-475 -2750);
DISPLAY 1.021277 (-475 -2750);
DISPLAY INVISIBLE (-475 -2750);
FORCEPROP 2 LAST $SEC 1
J 2
(-550 -2750);
DISPLAY 0.680851 (-550 -2750);
PAINT MONO (-550 -2750);
DISPLAY INVISIBLE (-550 -2750);
FORCEPROP 2 LAST CDS_SEC 1
J 2
(-550 -2750);
DISPLAY 0.680851 (-550 -2750);
DISPLAY INVISIBLE (-550 -2750);
FORCEADD Q_CAP_DIFFBUS..2
R 2
(-725 -2875);
FORCEPROP 1 LAST PART_NUMBER SP_CH4221MEE01
J 2
(-841 -2787);
DISPLAY 0.574468 (-841 -2787);
PAINT GREEN (-841 -2787);
DISPLAY INVISIBLE (-841 -2787);
FORCEPROP 2 LAST VALUE DIFF BUS_0.22UF
J 2
(-875 -2875);
DISPLAY 0.553191 (-875 -2875);
FORCEPROP 1 LAST $LOCATION C170
J 2
(-491 -2858);
DISPLAY 0.723404 (-491 -2858);
PAINT GREEN (-491 -2858);
FORCEPROP 2 LASTPIN (-650 -2875) $PN 1
J 0
(-640 -2865);
DISPLAY 0.808511 (-640 -2865);
FORCEPROP 2 LASTPIN (-800 -2875) $PN 2
J 2
(-810 -2865);
DISPLAY 0.808511 (-810 -2865);
FORCEPROP 2 LAST TOLERANCE 20%
J 2
(-800 -2825);
DISPLAY 0.553191 (-800 -2825);
DISPLAY INVISIBLE (-800 -2825);
FORCEPROP 2 LAST PACK_TYPE C0201
J 2
(-900 -2825);
DISPLAY 0.553191 (-900 -2825);
DISPLAY INVISIBLE (-900 -2825);
FORCEPROP 1 LAST MATERIAL X6S
J 2
(-716 -2796);
DISPLAY 0.574468 (-716 -2796);
PAINT GREEN (-716 -2796);
DISPLAY INVISIBLE (-716 -2796);
FORCEPROP 2 LAST VOLTAGE 6.3V
J 2
(-1075 -2825);
DISPLAY 0.553191 (-1075 -2825);
DISPLAY INVISIBLE (-1075 -2825);
FORCEPROP 1 LAST CDS_LMAN_SYM_OUTLINE -25,50,25,-50
J 2
(-725 -2875);
DISPLAY 0.468085 (-725 -2875);
PAINT GREEN (-725 -2875);
DISPLAY INVISIBLE (-725 -2875);
FORCEPROP 2 LAST CDS_LIB pure_quanta
J 2
(-725 -2875);
DISPLAY INVISIBLE (-725 -2875);
FORCEPROP 1 LAST PIN_NAMES_ROTATE TRUE
J 2
(-725 -2875);
DISPLAY 0.489362 (-725 -2875);
PAINT GREEN (-725 -2875);
DISPLAY INVISIBLE (-725 -2875);
FORCEPROP 1 LAST PATH I128
J 2
(-725 -2875);
DISPLAY 0.723404 (-725 -2875);
DISPLAY INVISIBLE (-725 -2875);
FORCEPROP 1 LAST $LOCATION C170
J 0
(-475 -2800);
DISPLAY 1.021277 (-475 -2800);
DISPLAY INVISIBLE (-475 -2800);
FORCEPROP 2 LAST CDS_LOCATION C170
J 0
(-475 -2800);
DISPLAY 1.021277 (-475 -2800);
DISPLAY INVISIBLE (-475 -2800);
FORCEPROP 2 LAST $SEC 1
J 2
(-550 -2800);
DISPLAY 0.680851 (-550 -2800);
PAINT MONO (-550 -2800);
DISPLAY INVISIBLE (-550 -2800);
FORCEPROP 2 LAST CDS_SEC 1
J 2
(-550 -2800);
DISPLAY 0.680851 (-550 -2800);
DISPLAY INVISIBLE (-550 -2800);
FORCEADD TAP..1
R 2
(-1450 -1425);
FORCEPROP 3 LASTPIN (-1400 -1425) SIG_NAME DMI_CPU0_PCH_RX_DN<7>
J 0
(-1390 -1415);
DISPLAY 0.659574 (-1390 -1415);
PAINT MONO (-1390 -1415);
DISPLAY INVISIBLE (-1390 -1415);
FORCEPROP 1 LASTPIN (-1400 -1425) BN 7
J 2
(-1388 -1417);
DISPLAY 0.680851 (-1388 -1417);
PAINT GREEN (-1388 -1417);
FORCEPROP 2 LAST CDS_LIB standard
J 0
(-1450 -1425);
DISPLAY INVISIBLE (-1450 -1425);
FORCEPROP 1 LAST BODY_TYPE PLUMBING
J 2
(-1450 -1375);
DISPLAY 0.872340 (-1450 -1375);
PAINT GREEN (-1450 -1375);
DISPLAY INVISIBLE (-1450 -1375);
FORCEPROP 1 LAST HDL_TAP TRUE
J 2
(-1775 -1550);
DISPLAY 0.872340 (-1775 -1550);
DISPLAY INVISIBLE (-1775 -1550);
FORCEPROP 1 LAST PATH I129
J 2
(-1448 -1425);
DISPLAY 0.872340 (-1448 -1425);
PAINT GREEN (-1448 -1425);
DISPLAY INVISIBLE (-1448 -1425);
FORCEADD TAP..1
R 2
(-1450 775);
FORCEPROP 3 LASTPIN (-1400 775) SIG_NAME DMI_CPU0_PCH_TX_DN<3>
J 0
(-1390 785);
DISPLAY 0.659574 (-1390 785);
PAINT MONO (-1390 785);
DISPLAY INVISIBLE (-1390 785);
FORCEPROP 1 LASTPIN (-1400 775) BN 3
J 2
(-1388 783);
DISPLAY 0.680851 (-1388 783);
PAINT GREEN (-1388 783);
FORCEPROP 2 LAST CDS_LIB standard
J 0
(-1450 775);
DISPLAY INVISIBLE (-1450 775);
FORCEPROP 1 LAST BODY_TYPE PLUMBING
J 2
(-1450 825);
DISPLAY 0.872340 (-1450 825);
PAINT GREEN (-1450 825);
DISPLAY INVISIBLE (-1450 825);
FORCEPROP 1 LAST HDL_TAP TRUE
J 2
(-1775 650);
DISPLAY 0.872340 (-1775 650);
DISPLAY INVISIBLE (-1775 650);
FORCEPROP 1 LAST PATH I13
J 2
(-1448 775);
DISPLAY 0.872340 (-1448 775);
PAINT GREEN (-1448 775);
DISPLAY INVISIBLE (-1448 775);
FORCEADD TAP..1
R 2
(-1450 -1625);
FORCEPROP 3 LASTPIN (-1400 -1625) SIG_NAME DMI_CPU0_PCH_RX_DN<6>
J 0
(-1390 -1615);
DISPLAY 0.659574 (-1390 -1615);
PAINT MONO (-1390 -1615);
DISPLAY INVISIBLE (-1390 -1615);
FORCEPROP 1 LASTPIN (-1400 -1625) BN 6
J 2
(-1388 -1617);
DISPLAY 0.680851 (-1388 -1617);
PAINT GREEN (-1388 -1617);
FORCEPROP 2 LAST CDS_LIB standard
J 0
(-1450 -1625);
DISPLAY INVISIBLE (-1450 -1625);
FORCEPROP 1 LAST BODY_TYPE PLUMBING
J 2
(-1450 -1575);
DISPLAY 0.872340 (-1450 -1575);
PAINT GREEN (-1450 -1575);
DISPLAY INVISIBLE (-1450 -1575);
FORCEPROP 1 LAST HDL_TAP TRUE
J 2
(-1775 -1750);
DISPLAY 0.872340 (-1775 -1750);
DISPLAY INVISIBLE (-1775 -1750);
FORCEPROP 1 LAST PATH I130
J 2
(-1448 -1625);
DISPLAY 0.872340 (-1448 -1625);
PAINT GREEN (-1448 -1625);
DISPLAY INVISIBLE (-1448 -1625);
FORCEADD TAP..1
R 2
(-1700 -1475);
FORCEPROP 3 LASTPIN (-1650 -1475) SIG_NAME DMI_CPU0_PCH_RX_DP<7>
J 0
(-1640 -1465);
DISPLAY 0.659574 (-1640 -1465);
PAINT MONO (-1640 -1465);
DISPLAY INVISIBLE (-1640 -1465);
FORCEPROP 1 LASTPIN (-1650 -1475) BN 7
J 2
(-1638 -1467);
DISPLAY 0.680851 (-1638 -1467);
PAINT GREEN (-1638 -1467);
FORCEPROP 2 LAST CDS_LIB standard
J 0
(-1700 -1475);
DISPLAY INVISIBLE (-1700 -1475);
FORCEPROP 1 LAST BODY_TYPE PLUMBING
J 2
(-1700 -1425);
DISPLAY 0.872340 (-1700 -1425);
PAINT GREEN (-1700 -1425);
DISPLAY INVISIBLE (-1700 -1425);
FORCEPROP 1 LAST HDL_TAP TRUE
J 2
(-2025 -1600);
DISPLAY 0.872340 (-2025 -1600);
DISPLAY INVISIBLE (-2025 -1600);
FORCEPROP 1 LAST PATH I131
J 2
(-1698 -1475);
DISPLAY 0.872340 (-1698 -1475);
PAINT GREEN (-1698 -1475);
DISPLAY INVISIBLE (-1698 -1475);
FORCEADD TAP..1
R 2
(-1450 -1825);
FORCEPROP 3 LASTPIN (-1400 -1825) SIG_NAME DMI_CPU0_PCH_RX_DN<5>
J 0
(-1390 -1815);
DISPLAY 0.659574 (-1390 -1815);
PAINT MONO (-1390 -1815);
DISPLAY INVISIBLE (-1390 -1815);
FORCEPROP 1 LASTPIN (-1400 -1825) BN 5
J 2
(-1388 -1817);
DISPLAY 0.680851 (-1388 -1817);
PAINT GREEN (-1388 -1817);
FORCEPROP 2 LAST CDS_LIB standard
J 0
(-1450 -1825);
DISPLAY INVISIBLE (-1450 -1825);
FORCEPROP 1 LAST BODY_TYPE PLUMBING
J 2
(-1450 -1775);
DISPLAY 0.872340 (-1450 -1775);
PAINT GREEN (-1450 -1775);
DISPLAY INVISIBLE (-1450 -1775);
FORCEPROP 1 LAST HDL_TAP TRUE
J 2
(-1775 -1950);
DISPLAY 0.872340 (-1775 -1950);
DISPLAY INVISIBLE (-1775 -1950);
FORCEPROP 1 LAST PATH I132
J 2
(-1448 -1825);
DISPLAY 0.872340 (-1448 -1825);
PAINT GREEN (-1448 -1825);
DISPLAY INVISIBLE (-1448 -1825);
FORCEADD TAP..1
R 2
(-1700 -1875);
FORCEPROP 3 LASTPIN (-1650 -1875) SIG_NAME DMI_CPU0_PCH_RX_DP<5>
J 0
(-1640 -1865);
DISPLAY 0.659574 (-1640 -1865);
PAINT MONO (-1640 -1865);
DISPLAY INVISIBLE (-1640 -1865);
FORCEPROP 1 LASTPIN (-1650 -1875) BN 5
J 2
(-1638 -1867);
DISPLAY 0.680851 (-1638 -1867);
PAINT GREEN (-1638 -1867);
FORCEPROP 2 LAST CDS_LIB standard
J 0
(-1700 -1875);
DISPLAY INVISIBLE (-1700 -1875);
FORCEPROP 1 LAST BODY_TYPE PLUMBING
J 2
(-1700 -1825);
DISPLAY 0.872340 (-1700 -1825);
PAINT GREEN (-1700 -1825);
DISPLAY INVISIBLE (-1700 -1825);
FORCEPROP 1 LAST HDL_TAP TRUE
J 2
(-2025 -2000);
DISPLAY 0.872340 (-2025 -2000);
DISPLAY INVISIBLE (-2025 -2000);
FORCEPROP 1 LAST PATH I133
J 2
(-1698 -1875);
DISPLAY 0.872340 (-1698 -1875);
PAINT GREEN (-1698 -1875);
DISPLAY INVISIBLE (-1698 -1875);
FORCEADD TAP..1
R 2
(-1700 -1675);
FORCEPROP 3 LASTPIN (-1650 -1675) SIG_NAME DMI_CPU0_PCH_RX_DP<6>
J 0
(-1640 -1665);
DISPLAY 0.659574 (-1640 -1665);
PAINT MONO (-1640 -1665);
DISPLAY INVISIBLE (-1640 -1665);
FORCEPROP 1 LASTPIN (-1650 -1675) BN 6
J 2
(-1638 -1667);
DISPLAY 0.680851 (-1638 -1667);
PAINT GREEN (-1638 -1667);
FORCEPROP 2 LAST CDS_LIB standard
J 0
(-1700 -1675);
DISPLAY INVISIBLE (-1700 -1675);
FORCEPROP 1 LAST BODY_TYPE PLUMBING
J 2
(-1700 -1625);
DISPLAY 0.872340 (-1700 -1625);
PAINT GREEN (-1700 -1625);
DISPLAY INVISIBLE (-1700 -1625);
FORCEPROP 1 LAST HDL_TAP TRUE
J 2
(-2025 -1800);
DISPLAY 0.872340 (-2025 -1800);
DISPLAY INVISIBLE (-2025 -1800);
FORCEPROP 1 LAST PATH I134
J 2
(-1698 -1675);
DISPLAY 0.872340 (-1698 -1675);
PAINT GREEN (-1698 -1675);
DISPLAY INVISIBLE (-1698 -1675);
FORCEADD TAP..1
R 2
(-1450 -2025);
FORCEPROP 3 LASTPIN (-1400 -2025) SIG_NAME DMI_CPU0_PCH_RX_DN<4>
J 0
(-1390 -2015);
DISPLAY 0.659574 (-1390 -2015);
PAINT MONO (-1390 -2015);
DISPLAY INVISIBLE (-1390 -2015);
FORCEPROP 1 LASTPIN (-1400 -2025) BN 4
J 2
(-1388 -2017);
DISPLAY 0.680851 (-1388 -2017);
PAINT GREEN (-1388 -2017);
FORCEPROP 2 LAST CDS_LIB standard
J 0
(-1450 -2025);
DISPLAY INVISIBLE (-1450 -2025);
FORCEPROP 1 LAST BODY_TYPE PLUMBING
J 2
(-1450 -1975);
DISPLAY 0.872340 (-1450 -1975);
PAINT GREEN (-1450 -1975);
DISPLAY INVISIBLE (-1450 -1975);
FORCEPROP 1 LAST HDL_TAP TRUE
J 2
(-1775 -2150);
DISPLAY 0.872340 (-1775 -2150);
DISPLAY INVISIBLE (-1775 -2150);
FORCEPROP 1 LAST PATH I135
J 2
(-1448 -2025);
DISPLAY 0.872340 (-1448 -2025);
PAINT GREEN (-1448 -2025);
DISPLAY INVISIBLE (-1448 -2025);
FORCEADD TAP..1
R 2
(-1450 -2225);
FORCEPROP 3 LASTPIN (-1400 -2225) SIG_NAME DMI_CPU0_PCH_RX_DN<3>
J 0
(-1390 -2215);
DISPLAY 0.659574 (-1390 -2215);
PAINT MONO (-1390 -2215);
DISPLAY INVISIBLE (-1390 -2215);
FORCEPROP 1 LASTPIN (-1400 -2225) BN 3
J 2
(-1388 -2217);
DISPLAY 0.680851 (-1388 -2217);
PAINT GREEN (-1388 -2217);
FORCEPROP 2 LAST CDS_LIB standard
J 0
(-1450 -2225);
DISPLAY INVISIBLE (-1450 -2225);
FORCEPROP 1 LAST BODY_TYPE PLUMBING
J 2
(-1450 -2175);
DISPLAY 0.872340 (-1450 -2175);
PAINT GREEN (-1450 -2175);
DISPLAY INVISIBLE (-1450 -2175);
FORCEPROP 1 LAST HDL_TAP TRUE
J 2
(-1775 -2350);
DISPLAY 0.872340 (-1775 -2350);
DISPLAY INVISIBLE (-1775 -2350);
FORCEPROP 1 LAST PATH I136
J 2
(-1448 -2225);
DISPLAY 0.872340 (-1448 -2225);
PAINT GREEN (-1448 -2225);
DISPLAY INVISIBLE (-1448 -2225);
FORCEADD TAP..1
R 2
(-1450 -2425);
FORCEPROP 3 LASTPIN (-1400 -2425) SIG_NAME DMI_CPU0_PCH_RX_DN<2>
J 0
(-1390 -2415);
DISPLAY 0.659574 (-1390 -2415);
PAINT MONO (-1390 -2415);
DISPLAY INVISIBLE (-1390 -2415);
FORCEPROP 1 LASTPIN (-1400 -2425) BN 2
J 2
(-1388 -2417);
DISPLAY 0.680851 (-1388 -2417);
PAINT GREEN (-1388 -2417);
FORCEPROP 2 LAST CDS_LIB standard
J 0
(-1450 -2425);
DISPLAY INVISIBLE (-1450 -2425);
FORCEPROP 1 LAST BODY_TYPE PLUMBING
J 2
(-1450 -2375);
DISPLAY 0.872340 (-1450 -2375);
PAINT GREEN (-1450 -2375);
DISPLAY INVISIBLE (-1450 -2375);
FORCEPROP 1 LAST HDL_TAP TRUE
J 2
(-1775 -2550);
DISPLAY 0.872340 (-1775 -2550);
DISPLAY INVISIBLE (-1775 -2550);
FORCEPROP 1 LAST PATH I137
J 2
(-1448 -2425);
DISPLAY 0.872340 (-1448 -2425);
PAINT GREEN (-1448 -2425);
DISPLAY INVISIBLE (-1448 -2425);
FORCEADD TAP..1
R 2
(-1700 -2075);
FORCEPROP 3 LASTPIN (-1650 -2075) SIG_NAME DMI_CPU0_PCH_RX_DP<4>
J 0
(-1640 -2065);
DISPLAY 0.659574 (-1640 -2065);
PAINT MONO (-1640 -2065);
DISPLAY INVISIBLE (-1640 -2065);
FORCEPROP 1 LASTPIN (-1650 -2075) BN 4
J 2
(-1638 -2067);
DISPLAY 0.680851 (-1638 -2067);
PAINT GREEN (-1638 -2067);
FORCEPROP 2 LAST CDS_LIB standard
J 0
(-1700 -2075);
DISPLAY INVISIBLE (-1700 -2075);
FORCEPROP 1 LAST BODY_TYPE PLUMBING
J 2
(-1700 -2025);
DISPLAY 0.872340 (-1700 -2025);
PAINT GREEN (-1700 -2025);
DISPLAY INVISIBLE (-1700 -2025);
FORCEPROP 1 LAST HDL_TAP TRUE
J 2
(-2025 -2200);
DISPLAY 0.872340 (-2025 -2200);
DISPLAY INVISIBLE (-2025 -2200);
FORCEPROP 1 LAST PATH I138
J 2
(-1698 -2075);
DISPLAY 0.872340 (-1698 -2075);
PAINT GREEN (-1698 -2075);
DISPLAY INVISIBLE (-1698 -2075);
FORCEADD TAP..1
R 2
(-1700 -2275);
FORCEPROP 3 LASTPIN (-1650 -2275) SIG_NAME DMI_CPU0_PCH_RX_DP<3>
J 0
(-1640 -2265);
DISPLAY 0.659574 (-1640 -2265);
PAINT MONO (-1640 -2265);
DISPLAY INVISIBLE (-1640 -2265);
FORCEPROP 1 LASTPIN (-1650 -2275) BN 3
J 2
(-1638 -2267);
DISPLAY 0.680851 (-1638 -2267);
PAINT GREEN (-1638 -2267);
FORCEPROP 2 LAST CDS_LIB standard
J 0
(-1700 -2275);
DISPLAY INVISIBLE (-1700 -2275);
FORCEPROP 1 LAST BODY_TYPE PLUMBING
J 2
(-1700 -2225);
DISPLAY 0.872340 (-1700 -2225);
PAINT GREEN (-1700 -2225);
DISPLAY INVISIBLE (-1700 -2225);
FORCEPROP 1 LAST HDL_TAP TRUE
J 2
(-2025 -2400);
DISPLAY 0.872340 (-2025 -2400);
DISPLAY INVISIBLE (-2025 -2400);
FORCEPROP 1 LAST PATH I139
J 2
(-1698 -2275);
DISPLAY 0.872340 (-1698 -2275);
PAINT GREEN (-1698 -2275);
DISPLAY INVISIBLE (-1698 -2275);
FORCEADD TAP..1
R 2
(-1700 1125);
FORCEPROP 3 LASTPIN (-1650 1125) SIG_NAME DMI_CPU0_PCH_TX_DP<5>
J 0
(-1640 1135);
DISPLAY 0.659574 (-1640 1135);
PAINT MONO (-1640 1135);
DISPLAY INVISIBLE (-1640 1135);
FORCEPROP 1 LASTPIN (-1650 1125) BN 5
J 2
(-1638 1133);
DISPLAY 0.680851 (-1638 1133);
PAINT GREEN (-1638 1133);
FORCEPROP 2 LAST CDS_LIB standard
J 0
(-1700 1125);
DISPLAY INVISIBLE (-1700 1125);
FORCEPROP 1 LAST BODY_TYPE PLUMBING
J 2
(-1700 1175);
DISPLAY 0.872340 (-1700 1175);
PAINT GREEN (-1700 1175);
DISPLAY INVISIBLE (-1700 1175);
FORCEPROP 1 LAST HDL_TAP TRUE
J 2
(-2025 1000);
DISPLAY 0.872340 (-2025 1000);
DISPLAY INVISIBLE (-2025 1000);
FORCEPROP 1 LAST PATH I14
J 2
(-1698 1125);
DISPLAY 0.872340 (-1698 1125);
PAINT GREEN (-1698 1125);
DISPLAY INVISIBLE (-1698 1125);
FORCEADD TAP..1
R 2
(-1700 -2475);
FORCEPROP 3 LASTPIN (-1650 -2475) SIG_NAME DMI_CPU0_PCH_RX_DP<2>
J 0
(-1640 -2465);
DISPLAY 0.659574 (-1640 -2465);
PAINT MONO (-1640 -2465);
DISPLAY INVISIBLE (-1640 -2465);
FORCEPROP 1 LASTPIN (-1650 -2475) BN 2
J 2
(-1638 -2467);
DISPLAY 0.680851 (-1638 -2467);
PAINT GREEN (-1638 -2467);
FORCEPROP 2 LAST CDS_LIB standard
J 0
(-1700 -2475);
DISPLAY INVISIBLE (-1700 -2475);
FORCEPROP 1 LAST BODY_TYPE PLUMBING
J 2
(-1700 -2425);
DISPLAY 0.872340 (-1700 -2425);
PAINT GREEN (-1700 -2425);
DISPLAY INVISIBLE (-1700 -2425);
FORCEPROP 1 LAST HDL_TAP TRUE
J 2
(-2025 -2600);
DISPLAY 0.872340 (-2025 -2600);
DISPLAY INVISIBLE (-2025 -2600);
FORCEPROP 1 LAST PATH I140
J 2
(-1698 -2475);
DISPLAY 0.872340 (-1698 -2475);
PAINT GREEN (-1698 -2475);
DISPLAY INVISIBLE (-1698 -2475);
FORCEADD TAP..1
R 2
(-1450 -2625);
FORCEPROP 3 LASTPIN (-1400 -2625) SIG_NAME DMI_CPU0_PCH_RX_DN<1>
J 0
(-1390 -2615);
DISPLAY 0.659574 (-1390 -2615);
PAINT MONO (-1390 -2615);
DISPLAY INVISIBLE (-1390 -2615);
FORCEPROP 1 LASTPIN (-1400 -2625) BN 1
J 2
(-1388 -2617);
DISPLAY 0.680851 (-1388 -2617);
PAINT GREEN (-1388 -2617);
FORCEPROP 2 LAST CDS_LIB standard
J 0
(-1450 -2625);
DISPLAY INVISIBLE (-1450 -2625);
FORCEPROP 1 LAST BODY_TYPE PLUMBING
J 2
(-1450 -2575);
DISPLAY 0.872340 (-1450 -2575);
PAINT GREEN (-1450 -2575);
DISPLAY INVISIBLE (-1450 -2575);
FORCEPROP 1 LAST HDL_TAP TRUE
J 2
(-1775 -2750);
DISPLAY 0.872340 (-1775 -2750);
DISPLAY INVISIBLE (-1775 -2750);
FORCEPROP 1 LAST PATH I141
J 2
(-1448 -2625);
DISPLAY 0.872340 (-1448 -2625);
PAINT GREEN (-1448 -2625);
DISPLAY INVISIBLE (-1448 -2625);
FORCEADD TAP..1
R 2
(-1450 -2825);
FORCEPROP 3 LASTPIN (-1400 -2825) SIG_NAME DMI_CPU0_PCH_RX_DN<0>
J 0
(-1390 -2815);
DISPLAY 0.659574 (-1390 -2815);
PAINT MONO (-1390 -2815);
DISPLAY INVISIBLE (-1390 -2815);
FORCEPROP 1 LASTPIN (-1400 -2825) BN 0
J 2
(-1388 -2817);
DISPLAY 0.680851 (-1388 -2817);
PAINT GREEN (-1388 -2817);
FORCEPROP 2 LAST CDS_LIB standard
J 0
(-1450 -2825);
DISPLAY INVISIBLE (-1450 -2825);
FORCEPROP 1 LAST BODY_TYPE PLUMBING
J 2
(-1450 -2775);
DISPLAY 0.872340 (-1450 -2775);
PAINT GREEN (-1450 -2775);
DISPLAY INVISIBLE (-1450 -2775);
FORCEPROP 1 LAST HDL_TAP TRUE
J 2
(-1775 -2950);
DISPLAY 0.872340 (-1775 -2950);
DISPLAY INVISIBLE (-1775 -2950);
FORCEPROP 1 LAST PATH I142
J 2
(-1448 -2825);
DISPLAY 0.872340 (-1448 -2825);
PAINT GREEN (-1448 -2825);
DISPLAY INVISIBLE (-1448 -2825);
FORCEADD TAP..1
R 2
(-1700 -2675);
FORCEPROP 3 LASTPIN (-1650 -2675) SIG_NAME DMI_CPU0_PCH_RX_DP<1>
J 0
(-1640 -2665);
DISPLAY 0.659574 (-1640 -2665);
PAINT MONO (-1640 -2665);
DISPLAY INVISIBLE (-1640 -2665);
FORCEPROP 1 LASTPIN (-1650 -2675) BN 1
J 2
(-1638 -2667);
DISPLAY 0.680851 (-1638 -2667);
PAINT GREEN (-1638 -2667);
FORCEPROP 2 LAST CDS_LIB standard
J 0
(-1700 -2675);
DISPLAY INVISIBLE (-1700 -2675);
FORCEPROP 1 LAST BODY_TYPE PLUMBING
J 2
(-1700 -2625);
DISPLAY 0.872340 (-1700 -2625);
PAINT GREEN (-1700 -2625);
DISPLAY INVISIBLE (-1700 -2625);
FORCEPROP 1 LAST HDL_TAP TRUE
J 2
(-2025 -2800);
DISPLAY 0.872340 (-2025 -2800);
DISPLAY INVISIBLE (-2025 -2800);
FORCEPROP 1 LAST PATH I143
J 2
(-1698 -2675);
DISPLAY 0.872340 (-1698 -2675);
PAINT GREEN (-1698 -2675);
DISPLAY INVISIBLE (-1698 -2675);
FORCEADD TAP..1
R 2
(-1700 -2875);
FORCEPROP 3 LASTPIN (-1650 -2875) SIG_NAME DMI_CPU0_PCH_RX_DP<0>
J 0
(-1640 -2865);
DISPLAY 0.659574 (-1640 -2865);
PAINT MONO (-1640 -2865);
DISPLAY INVISIBLE (-1640 -2865);
FORCEPROP 1 LASTPIN (-1650 -2875) BN 0
J 2
(-1638 -2867);
DISPLAY 0.680851 (-1638 -2867);
PAINT GREEN (-1638 -2867);
FORCEPROP 2 LAST CDS_LIB standard
J 0
(-1700 -2875);
DISPLAY INVISIBLE (-1700 -2875);
FORCEPROP 1 LAST BODY_TYPE PLUMBING
J 2
(-1700 -2825);
DISPLAY 0.872340 (-1700 -2825);
PAINT GREEN (-1700 -2825);
DISPLAY INVISIBLE (-1700 -2825);
FORCEPROP 1 LAST HDL_TAP TRUE
J 2
(-2025 -3000);
DISPLAY 0.872340 (-2025 -3000);
DISPLAY INVISIBLE (-2025 -3000);
FORCEPROP 1 LAST PATH I144
J 2
(-1698 -2875);
DISPLAY 0.872340 (-1698 -2875);
PAINT GREEN (-1698 -2875);
DISPLAY INVISIBLE (-1698 -2875);
FORCEADD OFFPAGE..1
(-2650 -1400);
FORCEPROP 2 LAST $XR0 181 
J 0
(-2932 -1400);
DISPLAY 0.638298 (-2932 -1400);
PAINT MONO (-2932 -1400);
FORCEPROP 2 LAST CDS_LIB standard
J 0
(-2650 -1400);
DISPLAY INVISIBLE (-2650 -1400);
FORCEPROP 1 LAST OFFPAGE TRUE
J 0
(-2325 -1525);
DISPLAY 0.872340 (-2325 -1525);
DISPLAY INVISIBLE (-2325 -1525);
FORCEPROP 1 LAST COMMENT_BODY TRUE
J 0
(-2525 -1500);
DISPLAY 0.872340 (-2525 -1500);
PAINT GREEN (-2525 -1500);
DISPLAY INVISIBLE (-2525 -1500);
FORCEPROP 2 LAST PATH I145
J 0
(-2600 -1325);
DISPLAY 1.021277 (-2600 -1325);
DISPLAY INVISIBLE (-2600 -1325);
FORCEADD OFFPAGE..1
(-2650 -1450);
FORCEPROP 2 LAST $XR0 181 
J 0
(-2932 -1450);
DISPLAY 0.638298 (-2932 -1450);
PAINT MONO (-2932 -1450);
FORCEPROP 2 LAST CDS_LIB standard
J 0
(-2650 -1450);
DISPLAY INVISIBLE (-2650 -1450);
FORCEPROP 1 LAST OFFPAGE TRUE
J 0
(-2325 -1575);
DISPLAY 0.872340 (-2325 -1575);
DISPLAY INVISIBLE (-2325 -1575);
FORCEPROP 1 LAST COMMENT_BODY TRUE
J 0
(-2525 -1550);
DISPLAY 0.872340 (-2525 -1550);
PAINT GREEN (-2525 -1550);
DISPLAY INVISIBLE (-2525 -1550);
FORCEPROP 2 LAST PATH I146
J 0
(-2600 -1375);
DISPLAY 1.021277 (-2600 -1375);
DISPLAY INVISIBLE (-2600 -1375);
FORCEADD TAP..1
R 2
(-1700 1325);
FORCEPROP 3 LASTPIN (-1650 1325) SIG_NAME DMI_CPU0_PCH_TX_DP<6>
J 0
(-1640 1335);
DISPLAY 0.659574 (-1640 1335);
PAINT MONO (-1640 1335);
DISPLAY INVISIBLE (-1640 1335);
FORCEPROP 1 LASTPIN (-1650 1325) BN 6
J 2
(-1638 1333);
DISPLAY 0.680851 (-1638 1333);
PAINT GREEN (-1638 1333);
FORCEPROP 2 LAST CDS_LIB standard
J 0
(-1700 1325);
DISPLAY INVISIBLE (-1700 1325);
FORCEPROP 1 LAST BODY_TYPE PLUMBING
J 2
(-1700 1375);
DISPLAY 0.872340 (-1700 1375);
PAINT GREEN (-1700 1375);
DISPLAY INVISIBLE (-1700 1375);
FORCEPROP 1 LAST HDL_TAP TRUE
J 2
(-2025 1200);
DISPLAY 0.872340 (-2025 1200);
DISPLAY INVISIBLE (-2025 1200);
FORCEPROP 1 LAST PATH I15
J 2
(-1698 1325);
DISPLAY 0.872340 (-1698 1325);
PAINT GREEN (-1698 1325);
DISPLAY INVISIBLE (-1698 1325);
FORCEADD TAP..1
R 2
(-1450 975);
FORCEPROP 3 LASTPIN (-1400 975) SIG_NAME DMI_CPU0_PCH_TX_DN<4>
J 0
(-1390 985);
DISPLAY 0.659574 (-1390 985);
PAINT MONO (-1390 985);
DISPLAY INVISIBLE (-1390 985);
FORCEPROP 1 LASTPIN (-1400 975) BN 4
J 2
(-1388 983);
DISPLAY 0.680851 (-1388 983);
PAINT GREEN (-1388 983);
FORCEPROP 2 LAST CDS_LIB standard
J 0
(-1450 975);
DISPLAY INVISIBLE (-1450 975);
FORCEPROP 1 LAST BODY_TYPE PLUMBING
J 2
(-1450 1025);
DISPLAY 0.872340 (-1450 1025);
PAINT GREEN (-1450 1025);
DISPLAY INVISIBLE (-1450 1025);
FORCEPROP 1 LAST HDL_TAP TRUE
J 2
(-1775 850);
DISPLAY 0.872340 (-1775 850);
DISPLAY INVISIBLE (-1775 850);
FORCEPROP 1 LAST PATH I16
J 2
(-1448 975);
DISPLAY 0.872340 (-1448 975);
PAINT GREEN (-1448 975);
DISPLAY INVISIBLE (-1448 975);
FORCEADD TAP..1
R 2
(-1450 1175);
FORCEPROP 3 LASTPIN (-1400 1175) SIG_NAME DMI_CPU0_PCH_TX_DN<5>
J 0
(-1390 1185);
DISPLAY 0.659574 (-1390 1185);
PAINT MONO (-1390 1185);
DISPLAY INVISIBLE (-1390 1185);
FORCEPROP 1 LASTPIN (-1400 1175) BN 5
J 2
(-1388 1183);
DISPLAY 0.680851 (-1388 1183);
PAINT GREEN (-1388 1183);
FORCEPROP 2 LAST CDS_LIB standard
J 0
(-1450 1175);
DISPLAY INVISIBLE (-1450 1175);
FORCEPROP 1 LAST BODY_TYPE PLUMBING
J 2
(-1450 1225);
DISPLAY 0.872340 (-1450 1225);
PAINT GREEN (-1450 1225);
DISPLAY INVISIBLE (-1450 1225);
FORCEPROP 1 LAST HDL_TAP TRUE
J 2
(-1775 1050);
DISPLAY 0.872340 (-1775 1050);
DISPLAY INVISIBLE (-1775 1050);
FORCEPROP 1 LAST PATH I17
J 2
(-1448 1175);
DISPLAY 0.872340 (-1448 1175);
PAINT GREEN (-1448 1175);
DISPLAY INVISIBLE (-1448 1175);
FORCEADD TAP..1
R 2
(-1450 1375);
FORCEPROP 3 LASTPIN (-1400 1375) SIG_NAME DMI_CPU0_PCH_TX_DN<6>
J 0
(-1390 1385);
DISPLAY 0.659574 (-1390 1385);
PAINT MONO (-1390 1385);
DISPLAY INVISIBLE (-1390 1385);
FORCEPROP 1 LASTPIN (-1400 1375) BN 6
J 2
(-1388 1383);
DISPLAY 0.680851 (-1388 1383);
PAINT GREEN (-1388 1383);
FORCEPROP 2 LAST CDS_LIB standard
J 0
(-1450 1375);
DISPLAY INVISIBLE (-1450 1375);
FORCEPROP 1 LAST BODY_TYPE PLUMBING
J 2
(-1450 1425);
DISPLAY 0.872340 (-1450 1425);
PAINT GREEN (-1450 1425);
DISPLAY INVISIBLE (-1450 1425);
FORCEPROP 1 LAST HDL_TAP TRUE
J 2
(-1775 1250);
DISPLAY 0.872340 (-1775 1250);
DISPLAY INVISIBLE (-1775 1250);
FORCEPROP 1 LAST PATH I18
J 2
(-1448 1375);
DISPLAY 0.872340 (-1448 1375);
PAINT GREEN (-1448 1375);
DISPLAY INVISIBLE (-1448 1375);
FORCEADD TAP..1
R 2
(-1700 1525);
FORCEPROP 3 LASTPIN (-1650 1525) SIG_NAME DMI_CPU0_PCH_TX_DP<7>
J 0
(-1640 1535);
DISPLAY 0.659574 (-1640 1535);
PAINT MONO (-1640 1535);
DISPLAY INVISIBLE (-1640 1535);
FORCEPROP 1 LASTPIN (-1650 1525) BN 7
J 2
(-1638 1533);
DISPLAY 0.680851 (-1638 1533);
PAINT GREEN (-1638 1533);
FORCEPROP 2 LAST CDS_LIB standard
J 0
(-1700 1525);
DISPLAY INVISIBLE (-1700 1525);
FORCEPROP 1 LAST BODY_TYPE PLUMBING
J 2
(-1700 1575);
DISPLAY 0.872340 (-1700 1575);
PAINT GREEN (-1700 1575);
DISPLAY INVISIBLE (-1700 1575);
FORCEPROP 1 LAST HDL_TAP TRUE
J 2
(-2025 1400);
DISPLAY 0.872340 (-2025 1400);
DISPLAY INVISIBLE (-2025 1400);
FORCEPROP 1 LAST PATH I19
J 2
(-1698 1525);
DISPLAY 0.872340 (-1698 1525);
PAINT GREEN (-1698 1525);
DISPLAY INVISIBLE (-1698 1525);
FORCEADD OFFPAGE..1
(-2650 1550);
FORCEPROP 2 LAST $XR0 28 
J 0
(-2901 1550);
DISPLAY 0.638298 (-2901 1550);
PAINT MONO (-2901 1550);
FORCEPROP 2 LAST CDS_LIB standard
J 0
(-2650 1550);
DISPLAY INVISIBLE (-2650 1550);
FORCEPROP 1 LAST OFFPAGE TRUE
J 0
(-2325 1425);
DISPLAY 0.872340 (-2325 1425);
DISPLAY INVISIBLE (-2325 1425);
FORCEPROP 1 LAST COMMENT_BODY TRUE
J 0
(-2525 1450);
DISPLAY 0.872340 (-2525 1450);
PAINT GREEN (-2525 1450);
DISPLAY INVISIBLE (-2525 1450);
FORCEPROP 2 LAST PATH I2
J 0
(-2600 1625);
DISPLAY 1.021277 (-2600 1625);
DISPLAY INVISIBLE (-2600 1625);
FORCEADD TAP..1
R 2
(-1450 1575);
FORCEPROP 3 LASTPIN (-1400 1575) SIG_NAME DMI_CPU0_PCH_TX_DN<7>
J 0
(-1390 1585);
DISPLAY 0.659574 (-1390 1585);
PAINT MONO (-1390 1585);
DISPLAY INVISIBLE (-1390 1585);
FORCEPROP 1 LASTPIN (-1400 1575) BN 7
J 2
(-1388 1583);
DISPLAY 0.680851 (-1388 1583);
PAINT GREEN (-1388 1583);
FORCEPROP 2 LAST CDS_LIB standard
J 0
(-1450 1575);
DISPLAY INVISIBLE (-1450 1575);
FORCEPROP 1 LAST BODY_TYPE PLUMBING
J 2
(-1450 1625);
DISPLAY 0.872340 (-1450 1625);
PAINT GREEN (-1450 1625);
DISPLAY INVISIBLE (-1450 1625);
FORCEPROP 1 LAST HDL_TAP TRUE
J 2
(-1775 1450);
DISPLAY 0.872340 (-1775 1450);
DISPLAY INVISIBLE (-1775 1450);
FORCEPROP 1 LAST PATH I20
J 2
(-1448 1575);
DISPLAY 0.872340 (-1448 1575);
PAINT GREEN (-1448 1575);
DISPLAY INVISIBLE (-1448 1575);
FORCEADD Q_CAP_DIFFBUS..2
R 2
(-725 175);
FORCEPROP 1 LAST PART_NUMBER SP_CH4221MEE01
J 2
(-841 263);
DISPLAY 0.574468 (-841 263);
PAINT GREEN (-841 263);
DISPLAY INVISIBLE (-841 263);
FORCEPROP 2 LAST VALUE DIFF BUS_0.22UF
J 2
(-875 175);
DISPLAY 0.553191 (-875 175);
FORCEPROP 1 LAST $LOCATION C153
J 2
(-491 192);
DISPLAY 0.723404 (-491 192);
PAINT GREEN (-491 192);
FORCEPROP 2 LASTPIN (-650 175) $PN 1
J 0
(-640 185);
DISPLAY 0.808511 (-640 185);
FORCEPROP 2 LASTPIN (-800 175) $PN 2
J 2
(-810 185);
DISPLAY 0.808511 (-810 185);
FORCEPROP 2 LAST TOLERANCE 20%
J 2
(-800 225);
DISPLAY 0.553191 (-800 225);
DISPLAY INVISIBLE (-800 225);
FORCEPROP 2 LAST PACK_TYPE C0201
J 2
(-900 225);
DISPLAY 0.553191 (-900 225);
DISPLAY INVISIBLE (-900 225);
FORCEPROP 1 LAST MATERIAL X6S
J 2
(-716 254);
DISPLAY 0.574468 (-716 254);
PAINT GREEN (-716 254);
DISPLAY INVISIBLE (-716 254);
FORCEPROP 2 LAST VOLTAGE 6.3V
J 2
(-1075 225);
DISPLAY 0.553191 (-1075 225);
DISPLAY INVISIBLE (-1075 225);
FORCEPROP 1 LAST CDS_LMAN_SYM_OUTLINE -25,50,25,-50
J 2
(-725 175);
DISPLAY 0.468085 (-725 175);
PAINT GREEN (-725 175);
DISPLAY INVISIBLE (-725 175);
FORCEPROP 2 LAST CDS_LIB pure_quanta
J 2
(-725 175);
DISPLAY INVISIBLE (-725 175);
FORCEPROP 1 LAST PIN_NAMES_ROTATE TRUE
J 2
(-725 175);
DISPLAY 0.489362 (-725 175);
PAINT GREEN (-725 175);
DISPLAY INVISIBLE (-725 175);
FORCEPROP 1 LAST PATH I21
J 2
(-725 175);
DISPLAY 0.723404 (-725 175);
DISPLAY INVISIBLE (-725 175);
FORCEPROP 1 LAST $LOCATION C153
J 0
(-475 250);
DISPLAY 1.021277 (-475 250);
DISPLAY INVISIBLE (-475 250);
FORCEPROP 2 LAST CDS_LOCATION C153
J 0
(-475 250);
DISPLAY 1.021277 (-475 250);
DISPLAY INVISIBLE (-475 250);
FORCEPROP 2 LAST $SEC 1
J 2
(-550 250);
DISPLAY 0.680851 (-550 250);
PAINT MONO (-550 250);
DISPLAY INVISIBLE (-550 250);
FORCEPROP 2 LAST CDS_SEC 1
J 2
(-550 250);
DISPLAY 0.680851 (-550 250);
DISPLAY INVISIBLE (-550 250);
FORCEADD Q_CAP_DIFFBUS..2
R 2
(-725 125);
FORCEPROP 1 LAST PART_NUMBER SP_CH4221MEE01
J 2
(-841 213);
DISPLAY 0.574468 (-841 213);
PAINT GREEN (-841 213);
DISPLAY INVISIBLE (-841 213);
FORCEPROP 2 LAST VALUE DIFF BUS_0.22UF
J 2
(-875 125);
DISPLAY 0.553191 (-875 125);
FORCEPROP 1 LAST $LOCATION C154
J 2
(-491 142);
DISPLAY 0.723404 (-491 142);
PAINT GREEN (-491 142);
FORCEPROP 2 LASTPIN (-650 125) $PN 1
J 0
(-640 135);
DISPLAY 0.808511 (-640 135);
FORCEPROP 2 LASTPIN (-800 125) $PN 2
J 2
(-810 135);
DISPLAY 0.808511 (-810 135);
FORCEPROP 2 LAST TOLERANCE 20%
J 2
(-800 175);
DISPLAY 0.553191 (-800 175);
DISPLAY INVISIBLE (-800 175);
FORCEPROP 2 LAST PACK_TYPE C0201
J 2
(-900 175);
DISPLAY 0.553191 (-900 175);
DISPLAY INVISIBLE (-900 175);
FORCEPROP 1 LAST MATERIAL X6S
J 2
(-716 204);
DISPLAY 0.574468 (-716 204);
PAINT GREEN (-716 204);
DISPLAY INVISIBLE (-716 204);
FORCEPROP 2 LAST VOLTAGE 6.3V
J 2
(-1075 175);
DISPLAY 0.553191 (-1075 175);
DISPLAY INVISIBLE (-1075 175);
FORCEPROP 1 LAST CDS_LMAN_SYM_OUTLINE -25,50,25,-50
J 2
(-725 125);
DISPLAY 0.468085 (-725 125);
PAINT GREEN (-725 125);
DISPLAY INVISIBLE (-725 125);
FORCEPROP 2 LAST CDS_LIB pure_quanta
J 2
(-725 125);
DISPLAY INVISIBLE (-725 125);
FORCEPROP 1 LAST PIN_NAMES_ROTATE TRUE
J 2
(-725 125);
DISPLAY 0.489362 (-725 125);
PAINT GREEN (-725 125);
DISPLAY INVISIBLE (-725 125);
FORCEPROP 1 LAST PATH I22
J 2
(-725 125);
DISPLAY 0.723404 (-725 125);
DISPLAY INVISIBLE (-725 125);
FORCEPROP 1 LAST $LOCATION C154
J 0
(-475 200);
DISPLAY 1.021277 (-475 200);
DISPLAY INVISIBLE (-475 200);
FORCEPROP 2 LAST CDS_LOCATION C154
J 0
(-475 200);
DISPLAY 1.021277 (-475 200);
DISPLAY INVISIBLE (-475 200);
FORCEPROP 2 LAST $SEC 1
J 2
(-550 200);
DISPLAY 0.680851 (-550 200);
PAINT MONO (-550 200);
DISPLAY INVISIBLE (-550 200);
FORCEPROP 2 LAST CDS_SEC 1
J 2
(-550 200);
DISPLAY 0.680851 (-550 200);
DISPLAY INVISIBLE (-550 200);
FORCEADD Q_CAP_DIFFBUS..2
R 2
(-725 325);
FORCEPROP 1 LAST PART_NUMBER SP_CH4221MEE01
J 2
(-841 413);
DISPLAY 0.574468 (-841 413);
PAINT GREEN (-841 413);
DISPLAY INVISIBLE (-841 413);
FORCEPROP 2 LAST VALUE DIFF BUS_0.22UF
J 2
(-875 325);
DISPLAY 0.553191 (-875 325);
FORCEPROP 1 LAST $LOCATION C152
J 2
(-491 342);
DISPLAY 0.723404 (-491 342);
PAINT GREEN (-491 342);
FORCEPROP 2 LASTPIN (-650 325) $PN 1
J 0
(-640 335);
DISPLAY 0.808511 (-640 335);
FORCEPROP 2 LASTPIN (-800 325) $PN 2
J 2
(-810 335);
DISPLAY 0.808511 (-810 335);
FORCEPROP 2 LAST TOLERANCE 20%
J 2
(-800 375);
DISPLAY 0.553191 (-800 375);
DISPLAY INVISIBLE (-800 375);
FORCEPROP 2 LAST PACK_TYPE C0201
J 2
(-900 375);
DISPLAY 0.553191 (-900 375);
DISPLAY INVISIBLE (-900 375);
FORCEPROP 1 LAST MATERIAL X6S
J 2
(-716 404);
DISPLAY 0.574468 (-716 404);
PAINT GREEN (-716 404);
DISPLAY INVISIBLE (-716 404);
FORCEPROP 2 LAST VOLTAGE 6.3V
J 2
(-1075 375);
DISPLAY 0.553191 (-1075 375);
DISPLAY INVISIBLE (-1075 375);
FORCEPROP 1 LAST CDS_LMAN_SYM_OUTLINE -25,50,25,-50
J 2
(-725 325);
DISPLAY 0.468085 (-725 325);
PAINT GREEN (-725 325);
DISPLAY INVISIBLE (-725 325);
FORCEPROP 2 LAST CDS_LIB pure_quanta
J 2
(-725 325);
DISPLAY INVISIBLE (-725 325);
FORCEPROP 1 LAST PIN_NAMES_ROTATE TRUE
J 2
(-725 325);
DISPLAY 0.489362 (-725 325);
PAINT GREEN (-725 325);
DISPLAY INVISIBLE (-725 325);
FORCEPROP 1 LAST PATH I23
J 2
(-725 325);
DISPLAY 0.723404 (-725 325);
DISPLAY INVISIBLE (-725 325);
FORCEPROP 1 LAST $LOCATION C152
J 0
(-475 400);
DISPLAY 1.021277 (-475 400);
DISPLAY INVISIBLE (-475 400);
FORCEPROP 2 LAST CDS_LOCATION C152
J 0
(-475 400);
DISPLAY 1.021277 (-475 400);
DISPLAY INVISIBLE (-475 400);
FORCEPROP 2 LAST $SEC 1
J 2
(-550 400);
DISPLAY 0.680851 (-550 400);
PAINT MONO (-550 400);
DISPLAY INVISIBLE (-550 400);
FORCEPROP 2 LAST CDS_SEC 1
J 2
(-550 400);
DISPLAY 0.680851 (-550 400);
DISPLAY INVISIBLE (-550 400);
FORCEADD Q_CAP_DIFFBUS..2
R 2
(-725 375);
FORCEPROP 1 LAST PART_NUMBER SP_CH4221MEE01
J 2
(-841 463);
DISPLAY 0.574468 (-841 463);
PAINT GREEN (-841 463);
DISPLAY INVISIBLE (-841 463);
FORCEPROP 2 LAST VALUE DIFF BUS_0.22UF
J 2
(-875 375);
DISPLAY 0.553191 (-875 375);
FORCEPROP 1 LAST $LOCATION C151
J 2
(-491 392);
DISPLAY 0.723404 (-491 392);
PAINT GREEN (-491 392);
FORCEPROP 2 LASTPIN (-650 375) $PN 1
J 0
(-640 385);
DISPLAY 0.808511 (-640 385);
FORCEPROP 2 LASTPIN (-800 375) $PN 2
J 2
(-810 385);
DISPLAY 0.808511 (-810 385);
FORCEPROP 2 LAST TOLERANCE 20%
J 2
(-800 425);
DISPLAY 0.553191 (-800 425);
DISPLAY INVISIBLE (-800 425);
FORCEPROP 2 LAST PACK_TYPE C0201
J 2
(-900 425);
DISPLAY 0.553191 (-900 425);
DISPLAY INVISIBLE (-900 425);
FORCEPROP 1 LAST MATERIAL X6S
J 2
(-716 454);
DISPLAY 0.574468 (-716 454);
PAINT GREEN (-716 454);
DISPLAY INVISIBLE (-716 454);
FORCEPROP 2 LAST VOLTAGE 6.3V
J 2
(-1075 425);
DISPLAY 0.553191 (-1075 425);
DISPLAY INVISIBLE (-1075 425);
FORCEPROP 2 LAST CDS_LIB pure_quanta
J 2
(-725 375);
DISPLAY INVISIBLE (-725 375);
FORCEPROP 1 LAST CDS_LMAN_SYM_OUTLINE -25,50,25,-50
J 2
(-725 375);
DISPLAY 0.468085 (-725 375);
PAINT GREEN (-725 375);
DISPLAY INVISIBLE (-725 375);
FORCEPROP 1 LAST PIN_NAMES_ROTATE TRUE
J 2
(-725 375);
DISPLAY 0.489362 (-725 375);
PAINT GREEN (-725 375);
DISPLAY INVISIBLE (-725 375);
FORCEPROP 1 LAST PATH I24
J 2
(-725 375);
DISPLAY 0.723404 (-725 375);
DISPLAY INVISIBLE (-725 375);
FORCEPROP 1 LAST $LOCATION C151
J 0
(-475 450);
DISPLAY 1.021277 (-475 450);
DISPLAY INVISIBLE (-475 450);
FORCEPROP 2 LAST CDS_LOCATION C151
J 0
(-475 450);
DISPLAY 1.021277 (-475 450);
DISPLAY INVISIBLE (-475 450);
FORCEPROP 2 LAST $SEC 1
J 2
(-550 450);
DISPLAY 0.680851 (-550 450);
PAINT MONO (-550 450);
DISPLAY INVISIBLE (-550 450);
FORCEPROP 2 LAST CDS_SEC 1
J 2
(-550 450);
DISPLAY 0.680851 (-550 450);
DISPLAY INVISIBLE (-550 450);
FORCEADD Q_CAP_DIFFBUS..2
R 2
(-725 575);
FORCEPROP 1 LAST PART_NUMBER SP_CH4221MEE01
J 2
(-841 663);
DISPLAY 0.574468 (-841 663);
PAINT GREEN (-841 663);
DISPLAY INVISIBLE (-841 663);
FORCEPROP 2 LAST VALUE DIFF BUS_0.22UF
J 2
(-875 575);
DISPLAY 0.553191 (-875 575);
FORCEPROP 1 LAST $LOCATION C149
J 2
(-491 592);
DISPLAY 0.723404 (-491 592);
PAINT GREEN (-491 592);
FORCEPROP 2 LASTPIN (-650 575) $PN 1
J 0
(-640 585);
DISPLAY 0.808511 (-640 585);
FORCEPROP 2 LASTPIN (-800 575) $PN 2
J 2
(-810 585);
DISPLAY 0.808511 (-810 585);
FORCEPROP 2 LAST TOLERANCE 20%
J 2
(-800 625);
DISPLAY 0.553191 (-800 625);
DISPLAY INVISIBLE (-800 625);
FORCEPROP 2 LAST PACK_TYPE C0201
J 2
(-900 625);
DISPLAY 0.553191 (-900 625);
DISPLAY INVISIBLE (-900 625);
FORCEPROP 1 LAST MATERIAL X6S
J 2
(-716 654);
DISPLAY 0.574468 (-716 654);
PAINT GREEN (-716 654);
DISPLAY INVISIBLE (-716 654);
FORCEPROP 2 LAST VOLTAGE 6.3V
J 2
(-1075 625);
DISPLAY 0.553191 (-1075 625);
DISPLAY INVISIBLE (-1075 625);
FORCEPROP 1 LAST CDS_LMAN_SYM_OUTLINE -25,50,25,-50
J 2
(-725 575);
DISPLAY 0.468085 (-725 575);
PAINT GREEN (-725 575);
DISPLAY INVISIBLE (-725 575);
FORCEPROP 2 LAST CDS_LIB pure_quanta
J 2
(-725 575);
DISPLAY INVISIBLE (-725 575);
FORCEPROP 1 LAST PIN_NAMES_ROTATE TRUE
J 2
(-725 575);
DISPLAY 0.489362 (-725 575);
PAINT GREEN (-725 575);
DISPLAY INVISIBLE (-725 575);
FORCEPROP 1 LAST PATH I25
J 2
(-725 575);
DISPLAY 0.723404 (-725 575);
DISPLAY INVISIBLE (-725 575);
FORCEPROP 1 LAST $LOCATION C149
J 0
(-475 650);
DISPLAY 1.021277 (-475 650);
DISPLAY INVISIBLE (-475 650);
FORCEPROP 2 LAST CDS_LOCATION C149
J 0
(-475 650);
DISPLAY 1.021277 (-475 650);
DISPLAY INVISIBLE (-475 650);
FORCEPROP 2 LAST $SEC 1
J 2
(-550 650);
DISPLAY 0.680851 (-550 650);
PAINT MONO (-550 650);
DISPLAY INVISIBLE (-550 650);
FORCEPROP 2 LAST CDS_SEC 1
J 2
(-550 650);
DISPLAY 0.680851 (-550 650);
DISPLAY INVISIBLE (-550 650);
FORCEADD Q_CAP_DIFFBUS..2
R 2
(-725 525);
FORCEPROP 1 LAST PART_NUMBER SP_CH4221MEE01
J 2
(-841 613);
DISPLAY 0.574468 (-841 613);
PAINT GREEN (-841 613);
DISPLAY INVISIBLE (-841 613);
FORCEPROP 2 LAST VALUE DIFF BUS_0.22UF
J 2
(-875 525);
DISPLAY 0.553191 (-875 525);
FORCEPROP 1 LAST $LOCATION C150
J 2
(-491 542);
DISPLAY 0.723404 (-491 542);
PAINT GREEN (-491 542);
FORCEPROP 2 LASTPIN (-650 525) $PN 1
J 0
(-640 535);
DISPLAY 0.808511 (-640 535);
FORCEPROP 2 LASTPIN (-800 525) $PN 2
J 2
(-810 535);
DISPLAY 0.808511 (-810 535);
FORCEPROP 2 LAST TOLERANCE 20%
J 2
(-800 575);
DISPLAY 0.553191 (-800 575);
DISPLAY INVISIBLE (-800 575);
FORCEPROP 2 LAST PACK_TYPE C0201
J 2
(-900 575);
DISPLAY 0.553191 (-900 575);
DISPLAY INVISIBLE (-900 575);
FORCEPROP 1 LAST MATERIAL X6S
J 2
(-716 604);
DISPLAY 0.574468 (-716 604);
PAINT GREEN (-716 604);
DISPLAY INVISIBLE (-716 604);
FORCEPROP 2 LAST VOLTAGE 6.3V
J 2
(-1075 575);
DISPLAY 0.553191 (-1075 575);
DISPLAY INVISIBLE (-1075 575);
FORCEPROP 1 LAST CDS_LMAN_SYM_OUTLINE -25,50,25,-50
J 2
(-725 525);
DISPLAY 0.468085 (-725 525);
PAINT GREEN (-725 525);
DISPLAY INVISIBLE (-725 525);
FORCEPROP 2 LAST CDS_LIB pure_quanta
J 2
(-725 525);
DISPLAY INVISIBLE (-725 525);
FORCEPROP 1 LAST PIN_NAMES_ROTATE TRUE
J 2
(-725 525);
DISPLAY 0.489362 (-725 525);
PAINT GREEN (-725 525);
DISPLAY INVISIBLE (-725 525);
FORCEPROP 1 LAST PATH I26
J 2
(-725 525);
DISPLAY 0.723404 (-725 525);
DISPLAY INVISIBLE (-725 525);
FORCEPROP 1 LAST $LOCATION C150
J 0
(-475 600);
DISPLAY 1.021277 (-475 600);
DISPLAY INVISIBLE (-475 600);
FORCEPROP 2 LAST CDS_LOCATION C150
J 0
(-475 600);
DISPLAY 1.021277 (-475 600);
DISPLAY INVISIBLE (-475 600);
FORCEPROP 2 LAST $SEC 1
J 2
(-550 600);
DISPLAY 0.680851 (-550 600);
PAINT MONO (-550 600);
DISPLAY INVISIBLE (-550 600);
FORCEPROP 2 LAST CDS_SEC 1
J 2
(-550 600);
DISPLAY 0.680851 (-550 600);
DISPLAY INVISIBLE (-550 600);
FORCEADD Q_CAP_DIFFBUS..2
R 2
(-725 725);
FORCEPROP 1 LAST PART_NUMBER SP_CH4221MEE01
J 2
(-841 813);
DISPLAY 0.574468 (-841 813);
PAINT GREEN (-841 813);
DISPLAY INVISIBLE (-841 813);
FORCEPROP 2 LAST VALUE DIFF BUS_0.22UF
J 2
(-875 725);
DISPLAY 0.553191 (-875 725);
FORCEPROP 1 LAST $LOCATION C148
J 2
(-491 742);
DISPLAY 0.723404 (-491 742);
PAINT GREEN (-491 742);
FORCEPROP 2 LASTPIN (-650 725) $PN 1
J 0
(-640 735);
DISPLAY 0.808511 (-640 735);
FORCEPROP 2 LASTPIN (-800 725) $PN 2
J 2
(-810 735);
DISPLAY 0.808511 (-810 735);
FORCEPROP 2 LAST TOLERANCE 20%
J 2
(-800 775);
DISPLAY 0.553191 (-800 775);
DISPLAY INVISIBLE (-800 775);
FORCEPROP 2 LAST PACK_TYPE C0201
J 2
(-900 775);
DISPLAY 0.553191 (-900 775);
DISPLAY INVISIBLE (-900 775);
FORCEPROP 1 LAST MATERIAL X6S
J 2
(-716 804);
DISPLAY 0.574468 (-716 804);
PAINT GREEN (-716 804);
DISPLAY INVISIBLE (-716 804);
FORCEPROP 2 LAST VOLTAGE 6.3V
J 2
(-1075 775);
DISPLAY 0.553191 (-1075 775);
DISPLAY INVISIBLE (-1075 775);
FORCEPROP 2 LAST CDS_LIB pure_quanta
J 2
(-725 725);
DISPLAY INVISIBLE (-725 725);
FORCEPROP 1 LAST CDS_LMAN_SYM_OUTLINE -25,50,25,-50
J 2
(-725 725);
DISPLAY 0.468085 (-725 725);
PAINT GREEN (-725 725);
DISPLAY INVISIBLE (-725 725);
FORCEPROP 1 LAST PIN_NAMES_ROTATE TRUE
J 2
(-725 725);
DISPLAY 0.489362 (-725 725);
PAINT GREEN (-725 725);
DISPLAY INVISIBLE (-725 725);
FORCEPROP 1 LAST PATH I27
J 2
(-725 725);
DISPLAY 0.723404 (-725 725);
DISPLAY INVISIBLE (-725 725);
FORCEPROP 1 LAST $LOCATION C148
J 0
(-475 800);
DISPLAY 1.021277 (-475 800);
DISPLAY INVISIBLE (-475 800);
FORCEPROP 2 LAST CDS_LOCATION C148
J 0
(-475 800);
DISPLAY 1.021277 (-475 800);
DISPLAY INVISIBLE (-475 800);
FORCEPROP 2 LAST $SEC 1
J 2
(-550 800);
DISPLAY 0.680851 (-550 800);
PAINT MONO (-550 800);
DISPLAY INVISIBLE (-550 800);
FORCEPROP 2 LAST CDS_SEC 1
J 2
(-550 800);
DISPLAY 0.680851 (-550 800);
DISPLAY INVISIBLE (-550 800);
FORCEADD Q_CAP_DIFFBUS..2
R 2
(-725 775);
FORCEPROP 1 LAST PART_NUMBER SP_CH4221MEE01
J 2
(-841 863);
DISPLAY 0.574468 (-841 863);
PAINT GREEN (-841 863);
DISPLAY INVISIBLE (-841 863);
FORCEPROP 2 LAST VALUE DIFF BUS_0.22UF
J 2
(-875 775);
DISPLAY 0.553191 (-875 775);
FORCEPROP 1 LAST $LOCATION C147
J 2
(-491 792);
DISPLAY 0.723404 (-491 792);
PAINT GREEN (-491 792);
FORCEPROP 2 LASTPIN (-650 775) $PN 1
J 0
(-640 785);
DISPLAY 0.808511 (-640 785);
FORCEPROP 2 LASTPIN (-800 775) $PN 2
J 2
(-810 785);
DISPLAY 0.808511 (-810 785);
FORCEPROP 2 LAST TOLERANCE 20%
J 2
(-800 825);
DISPLAY 0.553191 (-800 825);
DISPLAY INVISIBLE (-800 825);
FORCEPROP 2 LAST PACK_TYPE C0201
J 2
(-900 825);
DISPLAY 0.553191 (-900 825);
DISPLAY INVISIBLE (-900 825);
FORCEPROP 1 LAST MATERIAL X6S
J 2
(-716 854);
DISPLAY 0.574468 (-716 854);
PAINT GREEN (-716 854);
DISPLAY INVISIBLE (-716 854);
FORCEPROP 2 LAST VOLTAGE 6.3V
J 2
(-1075 825);
DISPLAY 0.553191 (-1075 825);
DISPLAY INVISIBLE (-1075 825);
FORCEPROP 2 LAST CDS_LIB pure_quanta
J 2
(-725 775);
DISPLAY INVISIBLE (-725 775);
FORCEPROP 1 LAST CDS_LMAN_SYM_OUTLINE -25,50,25,-50
J 2
(-725 775);
DISPLAY 0.468085 (-725 775);
PAINT GREEN (-725 775);
DISPLAY INVISIBLE (-725 775);
FORCEPROP 1 LAST PIN_NAMES_ROTATE TRUE
J 2
(-725 775);
DISPLAY 0.489362 (-725 775);
PAINT GREEN (-725 775);
DISPLAY INVISIBLE (-725 775);
FORCEPROP 1 LAST PATH I28
J 2
(-725 775);
DISPLAY 0.723404 (-725 775);
DISPLAY INVISIBLE (-725 775);
FORCEPROP 1 LAST $LOCATION C147
J 0
(-475 850);
DISPLAY 1.021277 (-475 850);
DISPLAY INVISIBLE (-475 850);
FORCEPROP 2 LAST CDS_LOCATION C147
J 0
(-475 850);
DISPLAY 1.021277 (-475 850);
DISPLAY INVISIBLE (-475 850);
FORCEPROP 2 LAST $SEC 1
J 2
(-550 850);
DISPLAY 0.680851 (-550 850);
PAINT MONO (-550 850);
DISPLAY INVISIBLE (-550 850);
FORCEPROP 2 LAST CDS_SEC 1
J 2
(-550 850);
DISPLAY 0.680851 (-550 850);
DISPLAY INVISIBLE (-550 850);
FORCEADD Q_CAP_DIFFBUS..2
R 2
(-725 925);
FORCEPROP 1 LAST PART_NUMBER SP_CH4221MEE01
J 2
(-841 1013);
DISPLAY 0.574468 (-841 1013);
PAINT GREEN (-841 1013);
DISPLAY INVISIBLE (-841 1013);
FORCEPROP 2 LAST VALUE DIFF BUS_0.22UF
J 2
(-875 925);
DISPLAY 0.553191 (-875 925);
FORCEPROP 1 LAST $LOCATION C146
J 2
(-491 942);
DISPLAY 0.723404 (-491 942);
PAINT GREEN (-491 942);
FORCEPROP 2 LASTPIN (-650 925) $PN 1
J 0
(-640 935);
DISPLAY 0.808511 (-640 935);
FORCEPROP 2 LASTPIN (-800 925) $PN 2
J 2
(-810 935);
DISPLAY 0.808511 (-810 935);
FORCEPROP 2 LAST TOLERANCE 20%
J 2
(-800 975);
DISPLAY 0.553191 (-800 975);
DISPLAY INVISIBLE (-800 975);
FORCEPROP 2 LAST PACK_TYPE C0201
J 2
(-900 975);
DISPLAY 0.553191 (-900 975);
DISPLAY INVISIBLE (-900 975);
FORCEPROP 1 LAST MATERIAL X6S
J 2
(-716 1004);
DISPLAY 0.574468 (-716 1004);
PAINT GREEN (-716 1004);
DISPLAY INVISIBLE (-716 1004);
FORCEPROP 2 LAST VOLTAGE 6.3V
J 2
(-1075 975);
DISPLAY 0.553191 (-1075 975);
DISPLAY INVISIBLE (-1075 975);
FORCEPROP 1 LAST CDS_LMAN_SYM_OUTLINE -25,50,25,-50
J 2
(-725 925);
DISPLAY 0.468085 (-725 925);
PAINT GREEN (-725 925);
DISPLAY INVISIBLE (-725 925);
FORCEPROP 2 LAST CDS_LIB pure_quanta
J 2
(-725 925);
DISPLAY INVISIBLE (-725 925);
FORCEPROP 1 LAST PIN_NAMES_ROTATE TRUE
J 2
(-725 925);
DISPLAY 0.489362 (-725 925);
PAINT GREEN (-725 925);
DISPLAY INVISIBLE (-725 925);
FORCEPROP 1 LAST PATH I29
J 2
(-725 925);
DISPLAY 0.723404 (-725 925);
DISPLAY INVISIBLE (-725 925);
FORCEPROP 1 LAST $LOCATION C146
J 0
(-475 1000);
DISPLAY 1.021277 (-475 1000);
DISPLAY INVISIBLE (-475 1000);
FORCEPROP 2 LAST CDS_LOCATION C146
J 0
(-475 1000);
DISPLAY 1.021277 (-475 1000);
DISPLAY INVISIBLE (-475 1000);
FORCEPROP 2 LAST $SEC 1
J 2
(-550 1000);
DISPLAY 0.680851 (-550 1000);
PAINT MONO (-550 1000);
DISPLAY INVISIBLE (-550 1000);
FORCEPROP 2 LAST CDS_SEC 1
J 2
(-550 1000);
DISPLAY 0.680851 (-550 1000);
DISPLAY INVISIBLE (-550 1000);
FORCEADD Q_CAP_DIFFBUS..2
R 2
(-725 975);
FORCEPROP 1 LAST PART_NUMBER SP_CH4221MEE01
J 2
(-841 1063);
DISPLAY 0.574468 (-841 1063);
PAINT GREEN (-841 1063);
DISPLAY INVISIBLE (-841 1063);
FORCEPROP 2 LAST VALUE DIFF BUS_0.22UF
J 2
(-875 975);
DISPLAY 0.553191 (-875 975);
FORCEPROP 1 LAST $LOCATION C145
J 2
(-491 992);
DISPLAY 0.723404 (-491 992);
PAINT GREEN (-491 992);
FORCEPROP 2 LASTPIN (-650 975) $PN 1
J 0
(-640 985);
DISPLAY 0.808511 (-640 985);
FORCEPROP 2 LASTPIN (-800 975) $PN 2
J 2
(-810 985);
DISPLAY 0.808511 (-810 985);
FORCEPROP 2 LAST TOLERANCE 20%
J 2
(-800 1025);
DISPLAY 0.553191 (-800 1025);
DISPLAY INVISIBLE (-800 1025);
FORCEPROP 2 LAST PACK_TYPE C0201
J 2
(-900 1025);
DISPLAY 0.553191 (-900 1025);
DISPLAY INVISIBLE (-900 1025);
FORCEPROP 1 LAST MATERIAL X6S
J 2
(-716 1054);
DISPLAY 0.574468 (-716 1054);
PAINT GREEN (-716 1054);
DISPLAY INVISIBLE (-716 1054);
FORCEPROP 2 LAST VOLTAGE 6.3V
J 2
(-1075 1025);
DISPLAY 0.553191 (-1075 1025);
DISPLAY INVISIBLE (-1075 1025);
FORCEPROP 1 LAST CDS_LMAN_SYM_OUTLINE -25,50,25,-50
J 2
(-725 975);
DISPLAY 0.468085 (-725 975);
PAINT GREEN (-725 975);
DISPLAY INVISIBLE (-725 975);
FORCEPROP 2 LAST CDS_LIB pure_quanta
J 2
(-725 975);
DISPLAY INVISIBLE (-725 975);
FORCEPROP 1 LAST PIN_NAMES_ROTATE TRUE
J 2
(-725 975);
DISPLAY 0.489362 (-725 975);
PAINT GREEN (-725 975);
DISPLAY INVISIBLE (-725 975);
FORCEPROP 1 LAST PATH I30
J 2
(-725 975);
DISPLAY 0.723404 (-725 975);
DISPLAY INVISIBLE (-725 975);
FORCEPROP 1 LAST $LOCATION C145
J 0
(-475 1050);
DISPLAY 1.021277 (-475 1050);
DISPLAY INVISIBLE (-475 1050);
FORCEPROP 2 LAST CDS_LOCATION C145
J 0
(-475 1050);
DISPLAY 1.021277 (-475 1050);
DISPLAY INVISIBLE (-475 1050);
FORCEPROP 2 LAST $SEC 1
J 2
(-550 1050);
DISPLAY 0.680851 (-550 1050);
PAINT MONO (-550 1050);
DISPLAY INVISIBLE (-550 1050);
FORCEPROP 2 LAST CDS_SEC 1
J 2
(-550 1050);
DISPLAY 0.680851 (-550 1050);
DISPLAY INVISIBLE (-550 1050);
FORCEADD Q_CAP_DIFFBUS..2
R 2
(-725 1125);
FORCEPROP 1 LAST PART_NUMBER SP_CH4221MEE01
J 2
(-841 1213);
DISPLAY 0.574468 (-841 1213);
PAINT GREEN (-841 1213);
DISPLAY INVISIBLE (-841 1213);
FORCEPROP 2 LAST VALUE DIFF BUS_0.22UF
J 2
(-875 1125);
DISPLAY 0.553191 (-875 1125);
FORCEPROP 1 LAST $LOCATION C144
J 2
(-491 1142);
DISPLAY 0.723404 (-491 1142);
PAINT GREEN (-491 1142);
FORCEPROP 2 LASTPIN (-650 1125) $PN 1
J 0
(-640 1135);
DISPLAY 0.808511 (-640 1135);
FORCEPROP 2 LASTPIN (-800 1125) $PN 2
J 2
(-810 1135);
DISPLAY 0.808511 (-810 1135);
FORCEPROP 2 LAST TOLERANCE 20%
J 2
(-800 1175);
DISPLAY 0.553191 (-800 1175);
DISPLAY INVISIBLE (-800 1175);
FORCEPROP 2 LAST PACK_TYPE C0201
J 2
(-900 1175);
DISPLAY 0.553191 (-900 1175);
DISPLAY INVISIBLE (-900 1175);
FORCEPROP 1 LAST MATERIAL X6S
J 2
(-716 1204);
DISPLAY 0.574468 (-716 1204);
PAINT GREEN (-716 1204);
DISPLAY INVISIBLE (-716 1204);
FORCEPROP 2 LAST VOLTAGE 6.3V
J 2
(-1075 1175);
DISPLAY 0.553191 (-1075 1175);
DISPLAY INVISIBLE (-1075 1175);
FORCEPROP 1 LAST CDS_LMAN_SYM_OUTLINE -25,50,25,-50
J 2
(-725 1125);
DISPLAY 0.468085 (-725 1125);
PAINT GREEN (-725 1125);
DISPLAY INVISIBLE (-725 1125);
FORCEPROP 2 LAST CDS_LIB pure_quanta
J 2
(-725 1125);
DISPLAY INVISIBLE (-725 1125);
FORCEPROP 1 LAST PIN_NAMES_ROTATE TRUE
J 2
(-725 1125);
DISPLAY 0.489362 (-725 1125);
PAINT GREEN (-725 1125);
DISPLAY INVISIBLE (-725 1125);
FORCEPROP 1 LAST PATH I31
J 2
(-725 1125);
DISPLAY 0.723404 (-725 1125);
DISPLAY INVISIBLE (-725 1125);
FORCEPROP 1 LAST $LOCATION C144
J 0
(-475 1200);
DISPLAY 1.021277 (-475 1200);
DISPLAY INVISIBLE (-475 1200);
FORCEPROP 2 LAST CDS_LOCATION C144
J 0
(-475 1200);
DISPLAY 1.021277 (-475 1200);
DISPLAY INVISIBLE (-475 1200);
FORCEPROP 2 LAST $SEC 1
J 2
(-550 1200);
DISPLAY 0.680851 (-550 1200);
PAINT MONO (-550 1200);
DISPLAY INVISIBLE (-550 1200);
FORCEPROP 2 LAST CDS_SEC 1
J 2
(-550 1200);
DISPLAY 0.680851 (-550 1200);
DISPLAY INVISIBLE (-550 1200);
FORCEADD Q_CAP_DIFFBUS..2
R 2
(-725 1175);
FORCEPROP 1 LAST PART_NUMBER SP_CH4221MEE01
J 2
(-841 1263);
DISPLAY 0.574468 (-841 1263);
PAINT GREEN (-841 1263);
DISPLAY INVISIBLE (-841 1263);
FORCEPROP 2 LAST VALUE DIFF BUS_0.22UF
J 2
(-875 1175);
DISPLAY 0.553191 (-875 1175);
FORCEPROP 1 LAST $LOCATION C143
J 2
(-491 1192);
DISPLAY 0.723404 (-491 1192);
PAINT GREEN (-491 1192);
FORCEPROP 2 LASTPIN (-650 1175) $PN 1
J 0
(-640 1185);
DISPLAY 0.808511 (-640 1185);
FORCEPROP 2 LASTPIN (-800 1175) $PN 2
J 2
(-810 1185);
DISPLAY 0.808511 (-810 1185);
FORCEPROP 2 LAST TOLERANCE 20%
J 2
(-800 1225);
DISPLAY 0.553191 (-800 1225);
DISPLAY INVISIBLE (-800 1225);
FORCEPROP 2 LAST PACK_TYPE C0201
J 2
(-900 1225);
DISPLAY 0.553191 (-900 1225);
DISPLAY INVISIBLE (-900 1225);
FORCEPROP 1 LAST MATERIAL X6S
J 2
(-716 1254);
DISPLAY 0.574468 (-716 1254);
PAINT GREEN (-716 1254);
DISPLAY INVISIBLE (-716 1254);
FORCEPROP 2 LAST VOLTAGE 6.3V
J 2
(-1075 1225);
DISPLAY 0.553191 (-1075 1225);
DISPLAY INVISIBLE (-1075 1225);
FORCEPROP 1 LAST CDS_LMAN_SYM_OUTLINE -25,50,25,-50
J 2
(-725 1175);
DISPLAY 0.468085 (-725 1175);
PAINT GREEN (-725 1175);
DISPLAY INVISIBLE (-725 1175);
FORCEPROP 2 LAST CDS_LIB pure_quanta
J 2
(-725 1175);
DISPLAY INVISIBLE (-725 1175);
FORCEPROP 1 LAST PIN_NAMES_ROTATE TRUE
J 2
(-725 1175);
DISPLAY 0.489362 (-725 1175);
PAINT GREEN (-725 1175);
DISPLAY INVISIBLE (-725 1175);
FORCEPROP 1 LAST PATH I32
J 2
(-725 1175);
DISPLAY 0.723404 (-725 1175);
DISPLAY INVISIBLE (-725 1175);
FORCEPROP 1 LAST $LOCATION C143
J 0
(-475 1250);
DISPLAY 1.021277 (-475 1250);
DISPLAY INVISIBLE (-475 1250);
FORCEPROP 2 LAST CDS_LOCATION C143
J 0
(-475 1250);
DISPLAY 1.021277 (-475 1250);
DISPLAY INVISIBLE (-475 1250);
FORCEPROP 2 LAST $SEC 1
J 2
(-550 1250);
DISPLAY 0.680851 (-550 1250);
PAINT MONO (-550 1250);
DISPLAY INVISIBLE (-550 1250);
FORCEPROP 2 LAST CDS_SEC 1
J 2
(-550 1250);
DISPLAY 0.680851 (-550 1250);
DISPLAY INVISIBLE (-550 1250);
FORCEADD Q_CAP_DIFFBUS..2
R 2
(-725 1325);
FORCEPROP 1 LAST PART_NUMBER SP_CH4221MEE01
J 2
(-841 1413);
DISPLAY 0.574468 (-841 1413);
PAINT GREEN (-841 1413);
DISPLAY INVISIBLE (-841 1413);
FORCEPROP 2 LAST VALUE DIFF BUS_0.22UF
J 2
(-875 1325);
DISPLAY 0.553191 (-875 1325);
FORCEPROP 1 LAST $LOCATION C142
J 2
(-491 1342);
DISPLAY 0.723404 (-491 1342);
PAINT GREEN (-491 1342);
FORCEPROP 2 LASTPIN (-650 1325) $PN 1
J 0
(-640 1335);
DISPLAY 0.808511 (-640 1335);
FORCEPROP 2 LASTPIN (-800 1325) $PN 2
J 2
(-810 1335);
DISPLAY 0.808511 (-810 1335);
FORCEPROP 2 LAST TOLERANCE 20%
J 2
(-800 1375);
DISPLAY 0.553191 (-800 1375);
DISPLAY INVISIBLE (-800 1375);
FORCEPROP 2 LAST PACK_TYPE C0201
J 2
(-900 1375);
DISPLAY 0.553191 (-900 1375);
DISPLAY INVISIBLE (-900 1375);
FORCEPROP 1 LAST MATERIAL X6S
J 2
(-716 1404);
DISPLAY 0.574468 (-716 1404);
PAINT GREEN (-716 1404);
DISPLAY INVISIBLE (-716 1404);
FORCEPROP 2 LAST VOLTAGE 6.3V
J 2
(-1075 1375);
DISPLAY 0.553191 (-1075 1375);
DISPLAY INVISIBLE (-1075 1375);
FORCEPROP 1 LAST CDS_LMAN_SYM_OUTLINE -25,50,25,-50
J 2
(-725 1325);
DISPLAY 0.468085 (-725 1325);
PAINT GREEN (-725 1325);
DISPLAY INVISIBLE (-725 1325);
FORCEPROP 2 LAST CDS_LIB pure_quanta
J 2
(-725 1325);
DISPLAY INVISIBLE (-725 1325);
FORCEPROP 1 LAST PIN_NAMES_ROTATE TRUE
J 2
(-725 1325);
DISPLAY 0.489362 (-725 1325);
PAINT GREEN (-725 1325);
DISPLAY INVISIBLE (-725 1325);
FORCEPROP 1 LAST PATH I33
J 2
(-725 1325);
DISPLAY 0.723404 (-725 1325);
DISPLAY INVISIBLE (-725 1325);
FORCEPROP 1 LAST $LOCATION C142
J 0
(-475 1400);
DISPLAY 1.021277 (-475 1400);
DISPLAY INVISIBLE (-475 1400);
FORCEPROP 2 LAST CDS_LOCATION C142
J 0
(-475 1400);
DISPLAY 1.021277 (-475 1400);
DISPLAY INVISIBLE (-475 1400);
FORCEPROP 2 LAST $SEC 1
J 2
(-550 1400);
DISPLAY 0.680851 (-550 1400);
PAINT MONO (-550 1400);
DISPLAY INVISIBLE (-550 1400);
FORCEPROP 2 LAST CDS_SEC 1
J 2
(-550 1400);
DISPLAY 0.680851 (-550 1400);
DISPLAY INVISIBLE (-550 1400);
FORCEADD Q_CAP_DIFFBUS..2
R 2
(-725 1375);
FORCEPROP 1 LAST PART_NUMBER SP_CH4221MEE01
J 2
(-841 1463);
DISPLAY 0.574468 (-841 1463);
PAINT GREEN (-841 1463);
DISPLAY INVISIBLE (-841 1463);
FORCEPROP 2 LAST VALUE DIFF BUS_0.22UF
J 2
(-875 1375);
DISPLAY 0.553191 (-875 1375);
FORCEPROP 1 LAST $LOCATION C141
J 2
(-491 1392);
DISPLAY 0.723404 (-491 1392);
PAINT GREEN (-491 1392);
FORCEPROP 2 LASTPIN (-650 1375) $PN 1
J 0
(-640 1385);
DISPLAY 0.808511 (-640 1385);
FORCEPROP 2 LASTPIN (-800 1375) $PN 2
J 2
(-810 1385);
DISPLAY 0.808511 (-810 1385);
FORCEPROP 2 LAST TOLERANCE 20%
J 2
(-800 1425);
DISPLAY 0.553191 (-800 1425);
DISPLAY INVISIBLE (-800 1425);
FORCEPROP 2 LAST PACK_TYPE C0201
J 2
(-900 1425);
DISPLAY 0.553191 (-900 1425);
DISPLAY INVISIBLE (-900 1425);
FORCEPROP 1 LAST MATERIAL X6S
J 2
(-716 1454);
DISPLAY 0.574468 (-716 1454);
PAINT GREEN (-716 1454);
DISPLAY INVISIBLE (-716 1454);
FORCEPROP 2 LAST VOLTAGE 6.3V
J 2
(-1075 1425);
DISPLAY 0.553191 (-1075 1425);
DISPLAY INVISIBLE (-1075 1425);
FORCEPROP 1 LAST CDS_LMAN_SYM_OUTLINE -25,50,25,-50
J 2
(-725 1375);
DISPLAY 0.468085 (-725 1375);
PAINT GREEN (-725 1375);
DISPLAY INVISIBLE (-725 1375);
FORCEPROP 2 LAST CDS_LIB pure_quanta
J 2
(-725 1375);
DISPLAY INVISIBLE (-725 1375);
FORCEPROP 1 LAST PIN_NAMES_ROTATE TRUE
J 2
(-725 1375);
DISPLAY 0.489362 (-725 1375);
PAINT GREEN (-725 1375);
DISPLAY INVISIBLE (-725 1375);
FORCEPROP 1 LAST PATH I34
J 2
(-725 1375);
DISPLAY 0.723404 (-725 1375);
DISPLAY INVISIBLE (-725 1375);
FORCEPROP 1 LAST $LOCATION C141
J 0
(-475 1450);
DISPLAY 1.021277 (-475 1450);
DISPLAY INVISIBLE (-475 1450);
FORCEPROP 2 LAST CDS_LOCATION C141
J 0
(-475 1450);
DISPLAY 1.021277 (-475 1450);
DISPLAY INVISIBLE (-475 1450);
FORCEPROP 2 LAST $SEC 1
J 2
(-550 1450);
DISPLAY 0.680851 (-550 1450);
PAINT MONO (-550 1450);
DISPLAY INVISIBLE (-550 1450);
FORCEPROP 2 LAST CDS_SEC 1
J 2
(-550 1450);
DISPLAY 0.680851 (-550 1450);
DISPLAY INVISIBLE (-550 1450);
FORCEADD Q_CAP_DIFFBUS..2
R 2
(-725 1575);
FORCEPROP 1 LAST PART_NUMBER SP_CH4221MEE01
J 2
(-841 1663);
DISPLAY 0.574468 (-841 1663);
PAINT GREEN (-841 1663);
DISPLAY INVISIBLE (-841 1663);
FORCEPROP 2 LAST VALUE DIFF BUS_0.22UF
J 2
(-875 1575);
DISPLAY 0.553191 (-875 1575);
FORCEPROP 1 LAST $LOCATION C139
J 2
(-491 1592);
DISPLAY 0.723404 (-491 1592);
PAINT GREEN (-491 1592);
FORCEPROP 2 LASTPIN (-650 1575) $PN 1
J 0
(-640 1585);
DISPLAY 0.808511 (-640 1585);
FORCEPROP 2 LASTPIN (-800 1575) $PN 2
J 2
(-810 1585);
DISPLAY 0.808511 (-810 1585);
FORCEPROP 2 LAST PACK_TYPE C0201
J 2
(-900 1625);
DISPLAY 0.553191 (-900 1625);
DISPLAY INVISIBLE (-900 1625);
FORCEPROP 1 LAST MATERIAL X6S
J 2
(-716 1654);
DISPLAY 0.574468 (-716 1654);
PAINT GREEN (-716 1654);
DISPLAY INVISIBLE (-716 1654);
FORCEPROP 2 LAST VOLTAGE 6.3V
J 2
(-1075 1625);
DISPLAY 0.553191 (-1075 1625);
DISPLAY INVISIBLE (-1075 1625);
FORCEPROP 2 LAST CDS_LIB pure_quanta
J 2
(-725 1575);
DISPLAY INVISIBLE (-725 1575);
FORCEPROP 1 LAST CDS_LMAN_SYM_OUTLINE -25,50,25,-50
J 2
(-725 1575);
DISPLAY 0.468085 (-725 1575);
PAINT GREEN (-725 1575);
DISPLAY INVISIBLE (-725 1575);
FORCEPROP 1 LAST PIN_NAMES_ROTATE TRUE
J 2
(-725 1575);
DISPLAY 0.489362 (-725 1575);
PAINT GREEN (-725 1575);
DISPLAY INVISIBLE (-725 1575);
FORCEPROP 2 LAST TOLERANCE 20%
J 2
(-800 1625);
DISPLAY 0.553191 (-800 1625);
DISPLAY INVISIBLE (-800 1625);
FORCEPROP 1 LAST PATH I35
J 2
(-725 1575);
DISPLAY 0.723404 (-725 1575);
DISPLAY INVISIBLE (-725 1575);
FORCEPROP 1 LAST $LOCATION C139
J 0
(-475 1650);
DISPLAY 1.021277 (-475 1650);
DISPLAY INVISIBLE (-475 1650);
FORCEPROP 2 LAST CDS_LOCATION C139
J 0
(-475 1650);
DISPLAY 1.021277 (-475 1650);
DISPLAY INVISIBLE (-475 1650);
FORCEPROP 2 LAST $SEC 1
J 2
(-550 1650);
DISPLAY 0.680851 (-550 1650);
PAINT MONO (-550 1650);
DISPLAY INVISIBLE (-550 1650);
FORCEPROP 2 LAST CDS_SEC 1
J 2
(-550 1650);
DISPLAY 0.680851 (-550 1650);
DISPLAY INVISIBLE (-550 1650);
FORCEADD Q_CAP_DIFFBUS..2
R 2
(-725 1525);
FORCEPROP 1 LAST PART_NUMBER SP_CH4221MEE01
J 2
(-841 1613);
DISPLAY 0.574468 (-841 1613);
PAINT GREEN (-841 1613);
DISPLAY INVISIBLE (-841 1613);
FORCEPROP 2 LAST VALUE DIFF BUS_0.22UF
J 2
(-875 1525);
DISPLAY 0.553191 (-875 1525);
FORCEPROP 1 LAST $LOCATION C1791
J 2
(-491 1542);
DISPLAY 0.723404 (-491 1542);
PAINT GREEN (-491 1542);
FORCEPROP 2 LASTPIN (-650 1525) $PN 1
J 0
(-640 1535);
DISPLAY 0.808511 (-640 1535);
FORCEPROP 2 LASTPIN (-800 1525) $PN 2
J 2
(-810 1535);
DISPLAY 0.808511 (-810 1535);
FORCEPROP 2 LAST TOLERANCE 20%
J 2
(-800 1575);
DISPLAY 0.553191 (-800 1575);
DISPLAY INVISIBLE (-800 1575);
FORCEPROP 2 LAST PACK_TYPE C0201
J 2
(-900 1575);
DISPLAY 0.553191 (-900 1575);
DISPLAY INVISIBLE (-900 1575);
FORCEPROP 1 LAST MATERIAL X6S
J 2
(-716 1604);
DISPLAY 0.574468 (-716 1604);
PAINT GREEN (-716 1604);
DISPLAY INVISIBLE (-716 1604);
FORCEPROP 2 LAST VOLTAGE 6.3V
J 2
(-1075 1575);
DISPLAY 0.553191 (-1075 1575);
DISPLAY INVISIBLE (-1075 1575);
FORCEPROP 1 LAST CDS_LMAN_SYM_OUTLINE -25,50,25,-50
J 2
(-725 1525);
DISPLAY 0.468085 (-725 1525);
PAINT GREEN (-725 1525);
DISPLAY INVISIBLE (-725 1525);
FORCEPROP 2 LAST CDS_LIB pure_quanta
J 2
(-725 1525);
DISPLAY INVISIBLE (-725 1525);
FORCEPROP 1 LAST PIN_NAMES_ROTATE TRUE
J 2
(-725 1525);
DISPLAY 0.489362 (-725 1525);
PAINT GREEN (-725 1525);
DISPLAY INVISIBLE (-725 1525);
FORCEPROP 1 LAST PATH I36
J 2
(-725 1525);
DISPLAY 0.723404 (-725 1525);
DISPLAY INVISIBLE (-725 1525);
FORCEPROP 2 LAST CDS_LOCATION C1791
J 0
(-475 1600);
DISPLAY 1.021277 (-475 1600);
DISPLAY INVISIBLE (-475 1600);
FORCEPROP 2 LAST $SEC 1
J 2
(-550 1600);
DISPLAY 0.680851 (-550 1600);
PAINT MONO (-550 1600);
DISPLAY INVISIBLE (-550 1600);
FORCEPROP 2 LAST CDS_SEC 1
J 2
(-550 1600);
DISPLAY 0.680851 (-550 1600);
DISPLAY INVISIBLE (-550 1600);
FORCEADD TAP..1
R 2
(-1700 125);
FORCEPROP 3 LASTPIN (-1650 125) SIG_NAME DMI_CPU0_PCH_TX_DP<0>
J 0
(-1640 135);
DISPLAY 0.659574 (-1640 135);
PAINT MONO (-1640 135);
DISPLAY INVISIBLE (-1640 135);
FORCEPROP 1 LASTPIN (-1650 125) BN 0
J 2
(-1638 133);
DISPLAY 0.680851 (-1638 133);
PAINT GREEN (-1638 133);
FORCEPROP 2 LAST CDS_LIB standard
J 0
(-1700 125);
DISPLAY INVISIBLE (-1700 125);
FORCEPROP 1 LAST BODY_TYPE PLUMBING
J 2
(-1700 175);
DISPLAY 0.872340 (-1700 175);
PAINT GREEN (-1700 175);
DISPLAY INVISIBLE (-1700 175);
FORCEPROP 1 LAST HDL_TAP TRUE
J 2
(-2025 0);
DISPLAY 0.872340 (-2025 0);
DISPLAY INVISIBLE (-2025 0);
FORCEPROP 1 LAST PATH I5
J 2
(-1698 125);
DISPLAY 0.872340 (-1698 125);
PAINT GREEN (-1698 125);
DISPLAY INVISIBLE (-1698 125);
FORCEADD TAP..1
R 2
(-1700 325);
FORCEPROP 3 LASTPIN (-1650 325) SIG_NAME DMI_CPU0_PCH_TX_DP<1>
J 0
(-1640 335);
DISPLAY 0.659574 (-1640 335);
PAINT MONO (-1640 335);
DISPLAY INVISIBLE (-1640 335);
FORCEPROP 1 LASTPIN (-1650 325) BN 1
J 2
(-1638 333);
DISPLAY 0.680851 (-1638 333);
PAINT GREEN (-1638 333);
FORCEPROP 2 LAST CDS_LIB standard
J 0
(-1700 325);
DISPLAY INVISIBLE (-1700 325);
FORCEPROP 1 LAST BODY_TYPE PLUMBING
J 2
(-1700 375);
DISPLAY 0.872340 (-1700 375);
PAINT GREEN (-1700 375);
DISPLAY INVISIBLE (-1700 375);
FORCEPROP 1 LAST HDL_TAP TRUE
J 2
(-2025 200);
DISPLAY 0.872340 (-2025 200);
DISPLAY INVISIBLE (-2025 200);
FORCEPROP 1 LAST PATH I6
J 2
(-1698 325);
DISPLAY 0.872340 (-1698 325);
PAINT GREEN (-1698 325);
DISPLAY INVISIBLE (-1698 325);
FORCEADD TAP..1
R 2
(-1450 175);
FORCEPROP 3 LASTPIN (-1400 175) SIG_NAME DMI_CPU0_PCH_TX_DN<0>
J 0
(-1390 185);
DISPLAY 0.659574 (-1390 185);
PAINT MONO (-1390 185);
DISPLAY INVISIBLE (-1390 185);
FORCEPROP 1 LASTPIN (-1400 175) BN 0
J 2
(-1388 183);
DISPLAY 0.680851 (-1388 183);
PAINT GREEN (-1388 183);
FORCEPROP 2 LAST CDS_LIB standard
J 0
(-1450 175);
DISPLAY INVISIBLE (-1450 175);
FORCEPROP 1 LAST BODY_TYPE PLUMBING
J 2
(-1450 225);
DISPLAY 0.872340 (-1450 225);
PAINT GREEN (-1450 225);
DISPLAY INVISIBLE (-1450 225);
FORCEPROP 1 LAST HDL_TAP TRUE
J 2
(-1775 50);
DISPLAY 0.872340 (-1775 50);
DISPLAY INVISIBLE (-1775 50);
FORCEPROP 1 LAST PATH I7
J 2
(-1448 175);
DISPLAY 0.872340 (-1448 175);
PAINT GREEN (-1448 175);
DISPLAY INVISIBLE (-1448 175);
FORCEADD TAP..1
(-175 1575);
FORCEPROP 3 LASTPIN (-225 1575) SIG_NAME DMI_CPU0_PCH_TX_C_DN<7>
J 0
(-215 1585);
DISPLAY 0.659574 (-215 1585);
PAINT MONO (-215 1585);
DISPLAY INVISIBLE (-215 1585);
FORCEPROP 1 LASTPIN (-225 1575) BN 7
J 0
(-237 1583);
DISPLAY 0.680851 (-237 1583);
PAINT GREEN (-237 1583);
FORCEPROP 2 LAST CDS_LIB standard
J 0
(-175 1575);
DISPLAY INVISIBLE (-175 1575);
FORCEPROP 1 LAST BODY_TYPE PLUMBING
J 0
(-175 1625);
DISPLAY 0.872340 (-175 1625);
PAINT GREEN (-175 1625);
DISPLAY INVISIBLE (-175 1625);
FORCEPROP 1 LAST HDL_TAP TRUE
J 0
(150 1450);
DISPLAY 0.872340 (150 1450);
DISPLAY INVISIBLE (150 1450);
FORCEPROP 1 LAST PATH I76
J 0
(-177 1575);
DISPLAY 0.872340 (-177 1575);
PAINT GREEN (-177 1575);
DISPLAY INVISIBLE (-177 1575);
FORCEADD TAP..1
(-175 1175);
FORCEPROP 3 LASTPIN (-225 1175) SIG_NAME DMI_CPU0_PCH_TX_C_DN<5>
J 0
(-215 1185);
DISPLAY 0.659574 (-215 1185);
PAINT MONO (-215 1185);
DISPLAY INVISIBLE (-215 1185);
FORCEPROP 1 LASTPIN (-225 1175) BN 5
J 0
(-237 1183);
DISPLAY 0.680851 (-237 1183);
PAINT GREEN (-237 1183);
FORCEPROP 2 LAST CDS_LIB standard
J 0
(-175 1175);
DISPLAY INVISIBLE (-175 1175);
FORCEPROP 1 LAST BODY_TYPE PLUMBING
J 0
(-175 1225);
DISPLAY 0.872340 (-175 1225);
PAINT GREEN (-175 1225);
DISPLAY INVISIBLE (-175 1225);
FORCEPROP 1 LAST HDL_TAP TRUE
J 0
(150 1050);
DISPLAY 0.872340 (150 1050);
DISPLAY INVISIBLE (150 1050);
FORCEPROP 1 LAST PATH I77
J 0
(-177 1175);
DISPLAY 0.872340 (-177 1175);
PAINT GREEN (-177 1175);
DISPLAY INVISIBLE (-177 1175);
FORCEADD TAP..1
(-175 1375);
FORCEPROP 3 LASTPIN (-225 1375) SIG_NAME DMI_CPU0_PCH_TX_C_DN<6>
J 0
(-215 1385);
DISPLAY 0.659574 (-215 1385);
PAINT MONO (-215 1385);
DISPLAY INVISIBLE (-215 1385);
FORCEPROP 1 LASTPIN (-225 1375) BN 6
J 0
(-237 1383);
DISPLAY 0.680851 (-237 1383);
PAINT GREEN (-237 1383);
FORCEPROP 2 LAST CDS_LIB standard
J 0
(-175 1375);
DISPLAY INVISIBLE (-175 1375);
FORCEPROP 1 LAST BODY_TYPE PLUMBING
J 0
(-175 1425);
DISPLAY 0.872340 (-175 1425);
PAINT GREEN (-175 1425);
DISPLAY INVISIBLE (-175 1425);
FORCEPROP 1 LAST HDL_TAP TRUE
J 0
(150 1250);
DISPLAY 0.872340 (150 1250);
DISPLAY INVISIBLE (150 1250);
FORCEPROP 1 LAST PATH I78
J 0
(-177 1375);
DISPLAY 0.872340 (-177 1375);
PAINT GREEN (-177 1375);
DISPLAY INVISIBLE (-177 1375);
FORCEADD TAP..1
(-175 775);
FORCEPROP 3 LASTPIN (-225 775) SIG_NAME DMI_CPU0_PCH_TX_C_DN<3>
J 0
(-215 785);
DISPLAY 0.659574 (-215 785);
PAINT MONO (-215 785);
DISPLAY INVISIBLE (-215 785);
FORCEPROP 1 LASTPIN (-225 775) BN 3
J 0
(-237 783);
DISPLAY 0.680851 (-237 783);
PAINT GREEN (-237 783);
FORCEPROP 2 LAST CDS_LIB standard
J 0
(-175 775);
DISPLAY INVISIBLE (-175 775);
FORCEPROP 1 LAST BODY_TYPE PLUMBING
J 0
(-175 825);
DISPLAY 0.872340 (-175 825);
PAINT GREEN (-175 825);
DISPLAY INVISIBLE (-175 825);
FORCEPROP 1 LAST HDL_TAP TRUE
J 0
(150 650);
DISPLAY 0.872340 (150 650);
DISPLAY INVISIBLE (150 650);
FORCEPROP 1 LAST PATH I79
J 0
(-177 775);
DISPLAY 0.872340 (-177 775);
PAINT GREEN (-177 775);
DISPLAY INVISIBLE (-177 775);
FORCEADD TAP..1
R 2
(-1450 375);
FORCEPROP 3 LASTPIN (-1400 375) SIG_NAME DMI_CPU0_PCH_TX_DN<1>
J 0
(-1390 385);
DISPLAY 0.659574 (-1390 385);
PAINT MONO (-1390 385);
DISPLAY INVISIBLE (-1390 385);
FORCEPROP 1 LASTPIN (-1400 375) BN 1
J 2
(-1388 383);
DISPLAY 0.680851 (-1388 383);
PAINT GREEN (-1388 383);
FORCEPROP 2 LAST CDS_LIB standard
J 0
(-1450 375);
DISPLAY INVISIBLE (-1450 375);
FORCEPROP 1 LAST BODY_TYPE PLUMBING
J 2
(-1450 425);
DISPLAY 0.872340 (-1450 425);
PAINT GREEN (-1450 425);
DISPLAY INVISIBLE (-1450 425);
FORCEPROP 1 LAST HDL_TAP TRUE
J 2
(-1775 250);
DISPLAY 0.872340 (-1775 250);
DISPLAY INVISIBLE (-1775 250);
FORCEPROP 1 LAST PATH I8
J 2
(-1448 375);
DISPLAY 0.872340 (-1448 375);
PAINT GREEN (-1448 375);
DISPLAY INVISIBLE (-1448 375);
FORCEADD TAP..1
(-175 975);
FORCEPROP 3 LASTPIN (-225 975) SIG_NAME DMI_CPU0_PCH_TX_C_DN<4>
J 0
(-215 985);
DISPLAY 0.659574 (-215 985);
PAINT MONO (-215 985);
DISPLAY INVISIBLE (-215 985);
FORCEPROP 1 LASTPIN (-225 975) BN 4
J 0
(-237 983);
DISPLAY 0.680851 (-237 983);
PAINT GREEN (-237 983);
FORCEPROP 2 LAST CDS_LIB standard
J 0
(-175 975);
DISPLAY INVISIBLE (-175 975);
FORCEPROP 1 LAST BODY_TYPE PLUMBING
J 0
(-175 1025);
DISPLAY 0.872340 (-175 1025);
PAINT GREEN (-175 1025);
DISPLAY INVISIBLE (-175 1025);
FORCEPROP 1 LAST HDL_TAP TRUE
J 0
(150 850);
DISPLAY 0.872340 (150 850);
DISPLAY INVISIBLE (150 850);
FORCEPROP 1 LAST PATH I80
J 0
(-177 975);
DISPLAY 0.872340 (-177 975);
PAINT GREEN (-177 975);
DISPLAY INVISIBLE (-177 975);
FORCEADD TAP..1
(-175 575);
FORCEPROP 3 LASTPIN (-225 575) SIG_NAME DMI_CPU0_PCH_TX_C_DN<2>
J 0
(-215 585);
DISPLAY 0.659574 (-215 585);
PAINT MONO (-215 585);
DISPLAY INVISIBLE (-215 585);
FORCEPROP 1 LASTPIN (-225 575) BN 2
J 0
(-237 583);
DISPLAY 0.680851 (-237 583);
PAINT GREEN (-237 583);
FORCEPROP 2 LAST CDS_LIB standard
J 0
(-175 575);
DISPLAY INVISIBLE (-175 575);
FORCEPROP 1 LAST BODY_TYPE PLUMBING
J 0
(-175 625);
DISPLAY 0.872340 (-175 625);
PAINT GREEN (-175 625);
DISPLAY INVISIBLE (-175 625);
FORCEPROP 1 LAST HDL_TAP TRUE
J 0
(150 450);
DISPLAY 0.872340 (150 450);
DISPLAY INVISIBLE (150 450);
FORCEPROP 1 LAST PATH I81
J 0
(-177 575);
DISPLAY 0.872340 (-177 575);
PAINT GREEN (-177 575);
DISPLAY INVISIBLE (-177 575);
FORCEADD TAP..1
(-175 375);
FORCEPROP 3 LASTPIN (-225 375) SIG_NAME DMI_CPU0_PCH_TX_C_DN<1>
J 0
(-215 385);
DISPLAY 0.659574 (-215 385);
PAINT MONO (-215 385);
DISPLAY INVISIBLE (-215 385);
FORCEPROP 1 LASTPIN (-225 375) BN 1
J 0
(-237 383);
DISPLAY 0.680851 (-237 383);
PAINT GREEN (-237 383);
FORCEPROP 2 LAST CDS_LIB standard
J 0
(-175 375);
DISPLAY INVISIBLE (-175 375);
FORCEPROP 1 LAST BODY_TYPE PLUMBING
J 0
(-175 425);
DISPLAY 0.872340 (-175 425);
PAINT GREEN (-175 425);
DISPLAY INVISIBLE (-175 425);
FORCEPROP 1 LAST HDL_TAP TRUE
J 0
(150 250);
DISPLAY 0.872340 (150 250);
DISPLAY INVISIBLE (150 250);
FORCEPROP 1 LAST PATH I82
J 0
(-177 375);
DISPLAY 0.872340 (-177 375);
PAINT GREEN (-177 375);
DISPLAY INVISIBLE (-177 375);
FORCEADD TAP..1
(-175 175);
FORCEPROP 3 LASTPIN (-225 175) SIG_NAME DMI_CPU0_PCH_TX_C_DN<0>
J 0
(-215 185);
DISPLAY 0.659574 (-215 185);
PAINT MONO (-215 185);
DISPLAY INVISIBLE (-215 185);
FORCEPROP 1 LASTPIN (-225 175) BN 0
J 0
(-237 183);
DISPLAY 0.680851 (-237 183);
PAINT GREEN (-237 183);
FORCEPROP 2 LAST CDS_LIB standard
J 0
(-175 175);
DISPLAY INVISIBLE (-175 175);
FORCEPROP 1 LAST BODY_TYPE PLUMBING
J 0
(-175 225);
DISPLAY 0.872340 (-175 225);
PAINT GREEN (-175 225);
DISPLAY INVISIBLE (-175 225);
FORCEPROP 1 LAST HDL_TAP TRUE
J 0
(150 50);
DISPLAY 0.872340 (150 50);
DISPLAY INVISIBLE (150 50);
FORCEPROP 1 LAST PATH I83
J 0
(-177 175);
DISPLAY 0.872340 (-177 175);
PAINT GREEN (-177 175);
DISPLAY INVISIBLE (-177 175);
FORCEADD TAP..1
(25 125);
FORCEPROP 3 LASTPIN (-25 125) SIG_NAME DMI_CPU0_PCH_TX_C_DP<0>
J 0
(-15 135);
DISPLAY 0.659574 (-15 135);
PAINT MONO (-15 135);
DISPLAY INVISIBLE (-15 135);
FORCEPROP 1 LASTPIN (-25 125) BN 0
J 0
(-37 133);
DISPLAY 0.680851 (-37 133);
PAINT GREEN (-37 133);
FORCEPROP 2 LAST CDS_LIB standard
J 0
(25 125);
DISPLAY INVISIBLE (25 125);
FORCEPROP 1 LAST BODY_TYPE PLUMBING
J 0
(25 175);
DISPLAY 0.872340 (25 175);
PAINT GREEN (25 175);
DISPLAY INVISIBLE (25 175);
FORCEPROP 1 LAST HDL_TAP TRUE
J 0
(350 0);
DISPLAY 0.872340 (350 0);
DISPLAY INVISIBLE (350 0);
FORCEPROP 1 LAST PATH I85
J 0
(23 125);
DISPLAY 0.872340 (23 125);
PAINT GREEN (23 125);
DISPLAY INVISIBLE (23 125);
FORCEADD TAP..1
(25 325);
FORCEPROP 3 LASTPIN (-25 325) SIG_NAME DMI_CPU0_PCH_TX_C_DP<1>
J 0
(-15 335);
DISPLAY 0.659574 (-15 335);
PAINT MONO (-15 335);
DISPLAY INVISIBLE (-15 335);
FORCEPROP 1 LASTPIN (-25 325) BN 1
J 0
(-37 333);
DISPLAY 0.680851 (-37 333);
PAINT GREEN (-37 333);
FORCEPROP 2 LAST CDS_LIB standard
J 0
(25 325);
DISPLAY INVISIBLE (25 325);
FORCEPROP 1 LAST BODY_TYPE PLUMBING
J 0
(25 375);
DISPLAY 0.872340 (25 375);
PAINT GREEN (25 375);
DISPLAY INVISIBLE (25 375);
FORCEPROP 1 LAST HDL_TAP TRUE
J 0
(350 200);
DISPLAY 0.872340 (350 200);
DISPLAY INVISIBLE (350 200);
FORCEPROP 1 LAST PATH I86
J 0
(23 325);
DISPLAY 0.872340 (23 325);
PAINT GREEN (23 325);
DISPLAY INVISIBLE (23 325);
FORCEADD TAP..1
(25 525);
FORCEPROP 3 LASTPIN (-25 525) SIG_NAME DMI_CPU0_PCH_TX_C_DP<2>
J 0
(-15 535);
DISPLAY 0.659574 (-15 535);
PAINT MONO (-15 535);
DISPLAY INVISIBLE (-15 535);
FORCEPROP 1 LASTPIN (-25 525) BN 2
J 0
(-37 533);
DISPLAY 0.680851 (-37 533);
PAINT GREEN (-37 533);
FORCEPROP 2 LAST CDS_LIB standard
J 0
(25 525);
DISPLAY INVISIBLE (25 525);
FORCEPROP 1 LAST BODY_TYPE PLUMBING
J 0
(25 575);
DISPLAY 0.872340 (25 575);
PAINT GREEN (25 575);
DISPLAY INVISIBLE (25 575);
FORCEPROP 1 LAST HDL_TAP TRUE
J 0
(350 400);
DISPLAY 0.872340 (350 400);
DISPLAY INVISIBLE (350 400);
FORCEPROP 1 LAST PATH I87
J 0
(23 525);
DISPLAY 0.872340 (23 525);
PAINT GREEN (23 525);
DISPLAY INVISIBLE (23 525);
FORCEADD TAP..1
(25 725);
FORCEPROP 3 LASTPIN (-25 725) SIG_NAME DMI_CPU0_PCH_TX_C_DP<3>
J 0
(-15 735);
DISPLAY 0.659574 (-15 735);
PAINT MONO (-15 735);
DISPLAY INVISIBLE (-15 735);
FORCEPROP 1 LASTPIN (-25 725) BN 3
J 0
(-37 733);
DISPLAY 0.680851 (-37 733);
PAINT GREEN (-37 733);
FORCEPROP 2 LAST CDS_LIB standard
J 0
(25 725);
DISPLAY INVISIBLE (25 725);
FORCEPROP 1 LAST BODY_TYPE PLUMBING
J 0
(25 775);
DISPLAY 0.872340 (25 775);
PAINT GREEN (25 775);
DISPLAY INVISIBLE (25 775);
FORCEPROP 1 LAST HDL_TAP TRUE
J 0
(350 600);
DISPLAY 0.872340 (350 600);
DISPLAY INVISIBLE (350 600);
FORCEPROP 1 LAST PATH I88
J 0
(23 725);
DISPLAY 0.872340 (23 725);
PAINT GREEN (23 725);
DISPLAY INVISIBLE (23 725);
FORCEADD TAP..1
(25 925);
FORCEPROP 3 LASTPIN (-25 925) SIG_NAME DMI_CPU0_PCH_TX_C_DP<4>
J 0
(-15 935);
DISPLAY 0.659574 (-15 935);
PAINT MONO (-15 935);
DISPLAY INVISIBLE (-15 935);
FORCEPROP 1 LASTPIN (-25 925) BN 4
J 0
(-37 933);
DISPLAY 0.680851 (-37 933);
PAINT GREEN (-37 933);
FORCEPROP 2 LAST CDS_LIB standard
J 0
(25 925);
DISPLAY INVISIBLE (25 925);
FORCEPROP 1 LAST BODY_TYPE PLUMBING
J 0
(25 975);
DISPLAY 0.872340 (25 975);
PAINT GREEN (25 975);
DISPLAY INVISIBLE (25 975);
FORCEPROP 1 LAST HDL_TAP TRUE
J 0
(350 800);
DISPLAY 0.872340 (350 800);
DISPLAY INVISIBLE (350 800);
FORCEPROP 1 LAST PATH I89
J 0
(23 925);
DISPLAY 0.872340 (23 925);
PAINT GREEN (23 925);
DISPLAY INVISIBLE (23 925);
FORCEADD TAP..1
R 2
(-1700 525);
FORCEPROP 3 LASTPIN (-1650 525) SIG_NAME DMI_CPU0_PCH_TX_DP<2>
J 0
(-1640 535);
DISPLAY 0.659574 (-1640 535);
PAINT MONO (-1640 535);
DISPLAY INVISIBLE (-1640 535);
FORCEPROP 1 LASTPIN (-1650 525) BN 2
J 2
(-1638 533);
DISPLAY 0.680851 (-1638 533);
PAINT GREEN (-1638 533);
FORCEPROP 2 LAST CDS_LIB standard
J 0
(-1700 525);
DISPLAY INVISIBLE (-1700 525);
FORCEPROP 1 LAST BODY_TYPE PLUMBING
J 2
(-1700 575);
DISPLAY 0.872340 (-1700 575);
PAINT GREEN (-1700 575);
DISPLAY INVISIBLE (-1700 575);
FORCEPROP 1 LAST HDL_TAP TRUE
J 2
(-2025 400);
DISPLAY 0.872340 (-2025 400);
DISPLAY INVISIBLE (-2025 400);
FORCEPROP 1 LAST PATH I9
J 2
(-1698 525);
DISPLAY 0.872340 (-1698 525);
PAINT GREEN (-1698 525);
DISPLAY INVISIBLE (-1698 525);
FORCEADD TAP..1
(25 1125);
FORCEPROP 3 LASTPIN (-25 1125) SIG_NAME DMI_CPU0_PCH_TX_C_DP<5>
J 0
(-15 1135);
DISPLAY 0.659574 (-15 1135);
PAINT MONO (-15 1135);
DISPLAY INVISIBLE (-15 1135);
FORCEPROP 1 LASTPIN (-25 1125) BN 5
J 0
(-37 1133);
DISPLAY 0.680851 (-37 1133);
PAINT GREEN (-37 1133);
FORCEPROP 2 LAST CDS_LIB standard
J 0
(25 1125);
DISPLAY INVISIBLE (25 1125);
FORCEPROP 1 LAST BODY_TYPE PLUMBING
J 0
(25 1175);
DISPLAY 0.872340 (25 1175);
PAINT GREEN (25 1175);
DISPLAY INVISIBLE (25 1175);
FORCEPROP 1 LAST HDL_TAP TRUE
J 0
(350 1000);
DISPLAY 0.872340 (350 1000);
DISPLAY INVISIBLE (350 1000);
FORCEPROP 1 LAST PATH I90
J 0
(23 1125);
DISPLAY 0.872340 (23 1125);
PAINT GREEN (23 1125);
DISPLAY INVISIBLE (23 1125);
FORCEADD TAP..1
(25 1325);
FORCEPROP 3 LASTPIN (-25 1325) SIG_NAME DMI_CPU0_PCH_TX_C_DP<6>
J 0
(-15 1335);
DISPLAY 0.659574 (-15 1335);
PAINT MONO (-15 1335);
DISPLAY INVISIBLE (-15 1335);
FORCEPROP 1 LASTPIN (-25 1325) BN 6
J 0
(-37 1333);
DISPLAY 0.680851 (-37 1333);
PAINT GREEN (-37 1333);
FORCEPROP 2 LAST CDS_LIB standard
J 0
(25 1325);
DISPLAY INVISIBLE (25 1325);
FORCEPROP 1 LAST BODY_TYPE PLUMBING
J 0
(25 1375);
DISPLAY 0.872340 (25 1375);
PAINT GREEN (25 1375);
DISPLAY INVISIBLE (25 1375);
FORCEPROP 1 LAST HDL_TAP TRUE
J 0
(350 1200);
DISPLAY 0.872340 (350 1200);
DISPLAY INVISIBLE (350 1200);
FORCEPROP 1 LAST PATH I91
J 0
(23 1325);
DISPLAY 0.872340 (23 1325);
PAINT GREEN (23 1325);
DISPLAY INVISIBLE (23 1325);
FORCEADD TAP..1
(25 1525);
FORCEPROP 3 LASTPIN (-25 1525) SIG_NAME DMI_CPU0_PCH_TX_C_DP<7>
J 0
(-15 1535);
DISPLAY 0.659574 (-15 1535);
PAINT MONO (-15 1535);
DISPLAY INVISIBLE (-15 1535);
FORCEPROP 1 LASTPIN (-25 1525) BN 7
J 0
(-37 1533);
DISPLAY 0.680851 (-37 1533);
PAINT GREEN (-37 1533);
FORCEPROP 2 LAST CDS_LIB standard
J 0
(25 1525);
DISPLAY INVISIBLE (25 1525);
FORCEPROP 1 LAST BODY_TYPE PLUMBING
J 0
(25 1575);
DISPLAY 0.872340 (25 1575);
PAINT GREEN (25 1575);
DISPLAY INVISIBLE (25 1575);
FORCEPROP 1 LAST HDL_TAP TRUE
J 0
(350 1400);
DISPLAY 0.872340 (350 1400);
DISPLAY INVISIBLE (350 1400);
FORCEPROP 1 LAST PATH I92
J 0
(23 1525);
DISPLAY 0.872340 (23 1525);
PAINT GREEN (23 1525);
DISPLAY INVISIBLE (23 1525);
FORCEADD OFFPAGE..2
(1025 1550);
FORCEPROP 2 LAST $XR0 181 
J 0
(1214 1550);
DISPLAY 0.638298 (1214 1550);
PAINT MONO (1214 1550);
FORCEPROP 2 LAST CDS_LIB standard
J 0
(1025 1550);
DISPLAY INVISIBLE (1025 1550);
FORCEPROP 1 LAST OFFPAGE TRUE
J 0
(1350 1425);
DISPLAY 0.872340 (1350 1425);
DISPLAY INVISIBLE (1350 1425);
FORCEPROP 1 LAST COMMENT_BODY TRUE
J 0
(980 1455);
DISPLAY 0.872340 (980 1455);
PAINT GREEN (980 1455);
DISPLAY INVISIBLE (980 1455);
FORCEPROP 2 LAST PATH I93
J 0
(1200 1625);
DISPLAY 1.021277 (1200 1625);
DISPLAY INVISIBLE (1200 1625);
FORCEADD OFFPAGE..2
(1025 1600);
FORCEPROP 2 LAST $XR0 181 
J 0
(1214 1600);
DISPLAY 0.638298 (1214 1600);
PAINT MONO (1214 1600);
FORCEPROP 2 LAST CDS_LIB standard
J 0
(1025 1600);
DISPLAY INVISIBLE (1025 1600);
FORCEPROP 1 LAST OFFPAGE TRUE
J 0
(1350 1475);
DISPLAY 0.872340 (1350 1475);
DISPLAY INVISIBLE (1350 1475);
FORCEPROP 1 LAST COMMENT_BODY TRUE
J 0
(980 1505);
DISPLAY 0.872340 (980 1505);
PAINT GREEN (980 1505);
DISPLAY INVISIBLE (980 1505);
FORCEPROP 2 LAST PATH I94
J 0
(1200 1675);
DISPLAY 1.021277 (1200 1675);
DISPLAY INVISIBLE (1200 1675);
FORCEADD TAP..1
(-175 -2625);
FORCEPROP 3 LASTPIN (-225 -2625) SIG_NAME DMI_CPU0_PCH_RX_C_DN<1>
J 0
(-215 -2615);
DISPLAY 0.659574 (-215 -2615);
PAINT MONO (-215 -2615);
DISPLAY INVISIBLE (-215 -2615);
FORCEPROP 1 LASTPIN (-225 -2625) BN 1
J 0
(-237 -2617);
DISPLAY 0.680851 (-237 -2617);
PAINT GREEN (-237 -2617);
FORCEPROP 2 LAST CDS_LIB standard
J 0
(-175 -2625);
DISPLAY INVISIBLE (-175 -2625);
FORCEPROP 1 LAST BODY_TYPE PLUMBING
J 0
(-175 -2575);
DISPLAY 0.872340 (-175 -2575);
PAINT GREEN (-175 -2575);
DISPLAY INVISIBLE (-175 -2575);
FORCEPROP 1 LAST HDL_TAP TRUE
J 0
(150 -2750);
DISPLAY 0.872340 (150 -2750);
DISPLAY INVISIBLE (150 -2750);
FORCEPROP 1 LAST PATH I95
J 0
(-177 -2625);
DISPLAY 0.872340 (-177 -2625);
PAINT GREEN (-177 -2625);
DISPLAY INVISIBLE (-177 -2625);
FORCEADD TAP..1
(-175 -2825);
FORCEPROP 3 LASTPIN (-225 -2825) SIG_NAME DMI_CPU0_PCH_RX_C_DN<0>
J 0
(-215 -2815);
DISPLAY 0.659574 (-215 -2815);
PAINT MONO (-215 -2815);
DISPLAY INVISIBLE (-215 -2815);
FORCEPROP 1 LASTPIN (-225 -2825) BN 0
J 0
(-237 -2817);
DISPLAY 0.680851 (-237 -2817);
PAINT GREEN (-237 -2817);
FORCEPROP 2 LAST CDS_LIB standard
J 0
(-175 -2825);
DISPLAY INVISIBLE (-175 -2825);
FORCEPROP 1 LAST BODY_TYPE PLUMBING
J 0
(-175 -2775);
DISPLAY 0.872340 (-175 -2775);
PAINT GREEN (-175 -2775);
DISPLAY INVISIBLE (-175 -2775);
FORCEPROP 1 LAST HDL_TAP TRUE
J 0
(150 -2950);
DISPLAY 0.872340 (150 -2950);
DISPLAY INVISIBLE (150 -2950);
FORCEPROP 1 LAST PATH I96
J 0
(-177 -2825);
DISPLAY 0.872340 (-177 -2825);
PAINT GREEN (-177 -2825);
DISPLAY INVISIBLE (-177 -2825);
FORCEADD OFFPAGE..2
(1025 -1400);
FORCEPROP 2 LAST $XR0 28 
J 0
(1214 -1400);
DISPLAY 0.638298 (1214 -1400);
PAINT MONO (1214 -1400);
FORCEPROP 2 LAST CDS_LIB standard
J 0
(1025 -1400);
DISPLAY INVISIBLE (1025 -1400);
FORCEPROP 1 LAST OFFPAGE TRUE
J 0
(1350 -1525);
DISPLAY 0.872340 (1350 -1525);
DISPLAY INVISIBLE (1350 -1525);
FORCEPROP 1 LAST COMMENT_BODY TRUE
J 0
(980 -1495);
DISPLAY 0.872340 (980 -1495);
PAINT GREEN (980 -1495);
DISPLAY INVISIBLE (980 -1495);
FORCEPROP 2 LAST PATH I97
J 0
(1200 -1325);
DISPLAY 1.021277 (1200 -1325);
DISPLAY INVISIBLE (1200 -1325);
FORCEADD OFFPAGE..2
(1025 -1450);
FORCEPROP 2 LAST $XR0 28 
J 0
(1214 -1450);
DISPLAY 0.638298 (1214 -1450);
PAINT MONO (1214 -1450);
FORCEPROP 2 LAST CDS_LIB standard
J 0
(1025 -1450);
DISPLAY INVISIBLE (1025 -1450);
FORCEPROP 1 LAST OFFPAGE TRUE
J 0
(1350 -1575);
DISPLAY 0.872340 (1350 -1575);
DISPLAY INVISIBLE (1350 -1575);
FORCEPROP 1 LAST COMMENT_BODY TRUE
J 0
(980 -1545);
DISPLAY 0.872340 (980 -1545);
PAINT GREEN (980 -1545);
DISPLAY INVISIBLE (980 -1545);
FORCEPROP 2 LAST PATH I98
J 0
(1200 -1375);
DISPLAY 1.021277 (1200 -1375);
DISPLAY INVISIBLE (1200 -1375);
FORCEADD TAP..1
(-175 -1425);
FORCEPROP 3 LASTPIN (-225 -1425) SIG_NAME DMI_CPU0_PCH_RX_C_DN<7>
J 0
(-215 -1415);
DISPLAY 0.659574 (-215 -1415);
PAINT MONO (-215 -1415);
DISPLAY INVISIBLE (-215 -1415);
FORCEPROP 1 LASTPIN (-225 -1425) BN 7
J 0
(-237 -1417);
DISPLAY 0.680851 (-237 -1417);
PAINT GREEN (-237 -1417);
FORCEPROP 2 LAST CDS_LIB standard
J 0
(-175 -1425);
DISPLAY INVISIBLE (-175 -1425);
FORCEPROP 1 LAST BODY_TYPE PLUMBING
J 0
(-175 -1375);
DISPLAY 0.872340 (-175 -1375);
PAINT GREEN (-175 -1375);
DISPLAY INVISIBLE (-175 -1375);
FORCEPROP 1 LAST HDL_TAP TRUE
J 0
(150 -1550);
DISPLAY 0.872340 (150 -1550);
DISPLAY INVISIBLE (150 -1550);
FORCEPROP 1 LAST PATH I99
J 0
(-177 -1425);
DISPLAY 0.872340 (-177 -1425);
PAINT GREEN (-177 -1425);
DISPLAY INVISIBLE (-177 -1425);
FORCEADD QUANTA_TITLE_BLOCK_C..1
(4025 -4325);
FORCEPROP 0 LAST CDS_CON_LAST_MODIFIED Fri Aug 25 14:02:50 2023
J 0
(2140 -4310);
DISPLAY INVISIBLE (2140 -4310);
FORCEPROP 1 LAST CUSTOM_TXT_CDS <CON_LAST_MODIFIED>
J 0
(2140 -4310);
DISPLAY 0.978723 (2140 -4310);
FORCEPROP 2 LAST CUSTOM_TXT_CDS <XR_PAGE_TITLE>
J 0
(-3865 925);
DISPLAY 0.638298 (-3865 925);
PAINT PINK (-3865 925);
DISPLAY INVISIBLE (-3865 925);
FORCEPROP 2 LAST CUSTOM_TXT_CDS <NAME_2>
J 0
(850 -4275);
FORCEPROP 2 LAST CUSTOM_TXT_CDS <NAME_1>
J 0
(850 -4150);
FORCEPROP 2 LAST CUSTOM_TXT_CDS <CON_PAGE_NUM> OF <CON_TOTAL_PAGES>
J 0
(3579 -4307);
DISPLAY 0.978723 (3579 -4307);
FORCEPROP 2 LAST CUSTOM_TXT_CDS <Q_REV>
J 0
(3841 -4222);
DISPLAY 1.212766 (3841 -4222);
FORCEPROP 2 LAST CUSTOM_TXT_CDS <Q_PROJ>
J 0
(1643 -4223);
DISPLAY 1.212766 (1643 -4223);
FORCEPROP 2 LAST CUSTOM_TXT_CDS <Q_NUMBER>
J 0
(2622 -4222);
DISPLAY 1.212766 (2622 -4222);
FORCEPROP 1 LAST Q_TITLE DMI AC-COUPLE CAPS
J 0
(-5316 -4299);
DISPLAY 2.446809 (-5316 -4299);
PAINT GREEN (-5316 -4299);
FORCEPROP 1 LAST Q_DEPT 
J 1
(262 -4276);
DISPLAY 1.957447 (262 -4276);
PAINT GREEN (262 -4276);
FORCEPROP 2 LAST CDS_XR_PAGE_TITLE CR-178 : @S9S_MB_2U_LIB.S9S_MB_2U(SCH_1):PAGE178
J 0
(-3865 925);
DISPLAY 0.638298 (-3865 925);
PAINT PINK (-3865 925);
DISPLAY INVISIBLE (-3865 925);
FORCEPROP 2 LAST PAGE_BORDER TRUE
J 0
(-3865 925);
DISPLAY 0.638298 (-3865 925);
PAINT PINK (-3865 925);
DISPLAY INVISIBLE (-3865 925);
FORCEPROP 1 LAST COMMENT_BODY TRUE
J 0
(4037 -4338);
DISPLAY 0.978723 (4037 -4338);
PAINT GREEN (4037 -4338);
DISPLAY INVISIBLE (4037 -4338);
FORCEPROP 1 LAST CDS_LMAN_SYM_OUTLINE -9475,6775,100,-125
J 0
(4025 -4325);
DISPLAY 0.468085 (4025 -4325);
PAINT GREEN (4025 -4325);
DISPLAY INVISIBLE (4025 -4325);
FORCEPROP 2 LAST CDS_LIB pure_quanta
J 0
(4025 -4325);
DISPLAY INVISIBLE (4025 -4325);
WIRE 17 -1 (-1750 1150)(-1750 1350);
WIRE 17 -1 (-1750 950)(-1750 1150);
WIRE 17 -1 (-1750 1350)(-1750 1550);
WIRE 17 -1 (-2600 1550)(-1750 1550);
FORCEPROP 2 LAST SIG_NAME DMI_CPU0_PCH_TX_DP<7:0>
J 0
(-2585 1560);
DISPLAY 0.680851 (-2585 1560);
PAINT WHITE (-2585 1560);
WIRE 17 -1 (75 -2650)(75 -2850);
WIRE 17 -1 (75 -2450)(75 -2650);
WIRE 17 -1 (75 -2250)(75 -2450);
WIRE 17 -1 (75 -2250)(75 -2050);
WIRE 17 -1 (75 -1850)(75 -2050);
WIRE 17 -1 (75 -1650)(75 -1850);
WIRE 17 -1 (75 -1450)(75 -1650);
WIRE 17 -1 (75 -1450)(975 -1450);
FORCEPROP 2 LAST SIG_NAME DMI_CPU0_PCH_RX_C_DP<7:0>
J 0
(115 -1440);
DISPLAY 0.680851 (115 -1440);
PAINT WHITE (115 -1440);
WIRE 17 -1 (-1750 -2850)(-1750 -2650);
WIRE 17 -1 (-1750 -2650)(-1750 -2450);
WIRE 17 -1 (-1750 -2450)(-1750 -2250);
WIRE 17 -1 (-1750 -2250)(-1750 -2050);
WIRE 17 -1 (-1750 -2050)(-1750 -1850);
WIRE 17 -1 (-1750 -1850)(-1750 -1650);
WIRE 17 -1 (-1750 -1650)(-1750 -1450);
WIRE 17 -1 (-2600 -1450)(-1750 -1450);
FORCEPROP 2 LAST SIG_NAME DMI_CPU0_PCH_RX_DP<7:0>
J 0
(-2560 -1440);
DISPLAY 0.680851 (-2560 -1440);
PAINT WHITE (-2560 -1440);
WIRE 17 -1 (-1500 -2600)(-1500 -2800);
WIRE 17 -1 (-1500 -2400)(-1500 -2600);
WIRE 17 -1 (-1500 -2200)(-1500 -2400);
WIRE 17 -1 (-1500 -2200)(-1500 -2000);
WIRE 17 -1 (-1500 -1800)(-1500 -2000);
WIRE 17 -1 (-1500 -1600)(-1500 -1800);
WIRE 17 -1 (-1500 -1400)(-1500 -1600);
WIRE 17 -1 (-2600 -1400)(-1500 -1400);
FORCEPROP 2 LAST SIG_NAME DMI_CPU0_PCH_RX_DN<7:0>
J 0
(-2560 -1390);
DISPLAY 0.680851 (-2560 -1390);
PAINT WHITE (-2560 -1390);
WIRE 17 -1 (-1500 1400)(-1500 1200);
WIRE 17 -1 (-1500 1600)(-1500 1400);
WIRE 17 -1 (-1500 1200)(-1500 1000);
WIRE 17 -1 (-1500 800)(-1500 1000);
WIRE 17 -1 (-2600 1600)(-1500 1600);
FORCEPROP 2 LAST SIG_NAME DMI_CPU0_PCH_TX_DN<7:0>
J 0
(-2585 1610);
DISPLAY 0.680851 (-2585 1610);
PAINT WHITE (-2585 1610);
WIRE 17 -1 (-1500 800)(-1500 600);
WIRE 17 -1 (-1500 600)(-1500 400);
WIRE 17 -1 (-1500 400)(-1500 200);
WIRE 17 -1 (-1750 750)(-1750 950);
WIRE 17 -1 (-1750 550)(-1750 750);
WIRE 17 -1 (-1750 350)(-1750 550);
WIRE 17 -1 (-1750 150)(-1750 350);
WIRE 17 -1 (-125 800)(-125 600);
WIRE 17 -1 (-125 800)(-125 1000);
WIRE 17 -1 (-125 600)(-125 400);
WIRE 17 -1 (-125 400)(-125 200);
WIRE 17 -1 (-125 1200)(-125 1000);
WIRE 17 -1 (-125 1400)(-125 1200);
WIRE 17 -1 (-125 1600)(-125 1400);
WIRE 17 -1 (-125 1600)(975 1600);
FORCEPROP 2 LAST SIG_NAME DMI_CPU0_PCH_TX_C_DN<7:0>
J 0
(140 1610);
DISPLAY 0.680851 (140 1610);
PAINT WHITE (140 1610);
WIRE 17 -1 (75 750)(75 950);
WIRE 17 -1 (75 750)(75 550);
WIRE 17 -1 (75 1150)(75 950);
WIRE 17 -1 (75 1350)(75 1150);
WIRE 17 -1 (75 550)(75 350);
WIRE 17 -1 (75 350)(75 150);
WIRE 17 -1 (75 1550)(75 1350);
WIRE 17 -1 (75 1550)(975 1550);
FORCEPROP 2 LAST SIG_NAME DMI_CPU0_PCH_TX_C_DP<7:0>
J 0
(140 1560);
DISPLAY 0.680851 (140 1560);
PAINT WHITE (140 1560);
WIRE 17 -1 (-125 -2200)(-125 -2400);
WIRE 17 -1 (-125 -2200)(-125 -2000);
WIRE 17 -1 (-125 -2400)(-125 -2600);
WIRE 17 -1 (-125 -2600)(-125 -2800);
WIRE 17 -1 (-125 -1800)(-125 -2000);
WIRE 17 -1 (-125 -1600)(-125 -1800);
WIRE 17 -1 (-125 -1400)(-125 -1600);
WIRE 17 -1 (-125 -1400)(975 -1400);
FORCEPROP 2 LAST SIG_NAME DMI_CPU0_PCH_RX_C_DN<7:0>
J 0
(115 -1390);
DISPLAY 0.680851 (115 -1390);
PAINT WHITE (115 -1390);
WIRE 16 -1 (-650 1575)(-225 1575);
WIRE 16 -1 (-800 1575)(-1400 1575);
WIRE 16 -1 (-800 -1625)(-1400 -1625);
WIRE 16 -1 (-650 -2625)(-225 -2625);
WIRE 16 -1 (-650 -2675)(-25 -2675);
WIRE 16 -1 (-800 175)(-1400 175);
WIRE 16 -1 (-650 525)(-25 525);
WIRE 16 -1 (-650 375)(-225 375);
WIRE 16 -1 (-650 325)(-25 325);
WIRE 16 -1 (-650 125)(-25 125);
WIRE 16 -1 (-800 -2625)(-1400 -2625);
WIRE 16 -1 (-650 -2075)(-25 -2075);
WIRE 16 -1 (-650 -2475)(-25 -2475);
WIRE 16 -1 (-800 -1825)(-1400 -1825);
WIRE 16 -1 (-800 -1875)(-1650 -1875);
WIRE 16 -1 (-650 -2025)(-225 -2025);
WIRE 16 -1 (-650 -2825)(-225 -2825);
WIRE 16 -1 (-650 -2225)(-225 -2225);
WIRE 16 -1 (-650 -2275)(-25 -2275);
WIRE 16 -1 (-800 -2075)(-1650 -2075);
WIRE 16 -1 (-800 525)(-1650 525);
WIRE 16 -1 (-650 -1425)(-225 -1425);
WIRE 16 -1 (-650 -1475)(-25 -1475);
WIRE 16 -1 (-650 -1625)(-225 -1625);
WIRE 16 -1 (-650 -1675)(-25 -1675);
WIRE 16 -1 (-650 -1825)(-225 -1825);
WIRE 16 -1 (-800 -2475)(-1650 -2475);
WIRE 16 -1 (-800 375)(-1400 375);
WIRE 16 -1 (-800 325)(-1650 325);
WIRE 16 -1 (-800 -2425)(-1400 -2425);
WIRE 16 -1 (-800 -2225)(-1400 -2225);
WIRE 16 -1 (-650 -2425)(-225 -2425);
WIRE 16 -1 (-800 -2025)(-1400 -2025);
WIRE 16 -1 (-800 -1475)(-1650 -1475);
WIRE 16 -1 (-800 -1425)(-1400 -1425);
WIRE 16 -1 (-650 -1875)(-25 -1875);
WIRE 16 -1 (-800 125)(-1650 125);
WIRE 16 -1 (-650 175)(-225 175);
WIRE 16 -1 (-650 1375)(-225 1375);
WIRE 16 -1 (-650 1325)(-25 1325);
WIRE 16 -1 (-650 1125)(-25 1125);
WIRE 16 -1 (-650 1525)(-25 1525);
WIRE 16 -1 (-650 1175)(-225 1175);
WIRE 16 -1 (-650 725)(-25 725);
WIRE 16 -1 (-650 925)(-25 925);
WIRE 16 -1 (-650 775)(-225 775);
WIRE 16 -1 (-650 975)(-225 975);
WIRE 16 -1 (-650 575)(-225 575);
WIRE 16 -1 (-800 1375)(-1400 1375);
WIRE 16 -1 (-800 1525)(-1650 1525);
WIRE 16 -1 (-800 725)(-1650 725);
WIRE 16 -1 (-800 925)(-1650 925);
WIRE 16 -1 (-800 975)(-1400 975);
WIRE 16 -1 (-800 575)(-1400 575);
WIRE 16 -1 (-800 775)(-1400 775);
WIRE 16 -1 (-800 1125)(-1650 1125);
WIRE 16 -1 (-800 1175)(-1400 1175);
WIRE 16 -1 (-800 -1675)(-1650 -1675);
WIRE 16 -1 (-800 -2275)(-1650 -2275);
WIRE 16 -1 (-800 -2675)(-1650 -2675);
WIRE 16 -1 (-800 -2825)(-1400 -2825);
WIRE 16 -1 (-800 -2875)(-1650 -2875);
WIRE 16 -1 (-650 -2875)(-25 -2875);
WIRE 16 -1 (-800 1325)(-1650 1325);
FORCENOTE
CPU0 DMI RX
(-1900 -3500) 0;
DISPLAY LEFT (-1900 -3500);
DISPLAY 4.148936 (-1900 -3500);
PAINT WHITE (-1900 -3500);
FORCENOTE
CPU0 DMI TX
(-1900 -500) 0;
DISPLAY LEFT (-1900 -500);
DISPLAY 4.148936 (-1900 -500);
PAINT WHITE (-1900 -500);
QUIT
